(kicad_sch
	(version 20250114)
	(generator "eeschema")
	(generator_version "9.0")
	(paper "A3")
	(title_block
		(title "OCuLink to PCIe adapter")
		(date "2025-06-18")
		(rev "1.0.0")
		(company "Antmicro Ltd")
		(comment 1 "www.antmicro.com")
	)
	(rectangle
		(start 330.2 45.72)
		(end 400.05 116.84)
		(stroke
			(width 0)
			(type default)
		)
		(fill
			(type none)
		)
	)
	(text "GREEN = USB-C PD OK\nRED = USB-C PD FAULT"
		(exclude_from_sim no)
		(at 283.21 62.484 0)
		(effects
			(font
				(size 1.27 1.27)
			)
		)
	)
	(text "USB-C connector"
		(exclude_from_sim no)
		(at 50.8 25.4 0)
		(effects
			(font
				(size 2 2)
				(thickness 0.4)
				(bold yes)
			)
			(justify left bottom)
		)
	)
	(text "f_{sw} = 400kHz"
		(exclude_from_sim no)
		(at 163.068 245.872 0)
		(effects
			(font
				(size 1.27 1.27)
			)
			(justify left bottom)
		)
	)
	(text "0.8V typ"
		(exclude_from_sim no)
		(at 225.806 213.36 0)
		(effects
			(font
				(size 1.27 1.27)
			)
			(justify left bottom)
		)
	)
	(text "USB-C PD Controller"
		(exclude_from_sim no)
		(at 254 25.4 0)
		(effects
			(font
				(size 2 2)
				(thickness 0.4)
				(bold yes)
			)
			(justify left bottom)
		)
	)
	(text "50kΩ sets the UFP VDO \ndata capability bit to 0"
		(exclude_from_sim no)
		(at 228.854 107.95 0)
		(effects
			(font
				(size 1.27 1.27)
			)
		)
	)
	(text "+12V DC/DC converter"
		(exclude_from_sim no)
		(at 173.99 177.8 0)
		(effects
			(font
				(size 2 2)
				(thickness 0.4)
				(bold yes)
			)
			(justify left bottom)
		)
	)
	(text "R_FB_H = R_FB_L * (V_OUT - V_FB) / V_FB \n10k * (12 - 0.8) / 0.8 = 140k\n"
		(exclude_from_sim no)
		(at 228.092 248.92 0)
		(effects
			(font
				(size 1.27 1.27)
			)
			(justify left bottom)
		)
	)
	(text "Power save mode enabled, \nVDD, VDRVPre-reg on"
		(exclude_from_sim no)
		(at 122.428 248.412 0)
		(effects
			(font
				(size 1.27 1.27)
			)
			(justify left bottom)
		)
	)
	(text "Note:\nPlace close to\nthe feedback \nresistors"
		(exclude_from_sim no)
		(at 250.444 226.822 0)
		(effects
			(font
				(size 1.27 1.27)
			)
			(justify left bottom)
		)
	)
	(text "Output current: max 7A"
		(exclude_from_sim no)
		(at 288.798 191.516 0)
		(effects
			(font
				(size 1.27 1.27)
			)
			(justify left bottom)
		)
	)
	(junction
		(at 115.57 194.31)
		(diameter 0)
		(color 0 0 0 0)
	)
	(junction
		(at 381 60.96)
		(diameter 0)
		(color 0 0 0 0)
	)
	(junction
		(at 248.92 101.6)
		(diameter 0)
		(color 0 0 0 0)
	)
	(junction
		(at 262.89 194.31)
		(diameter 0)
		(color 0 0 0 0)
	)
	(junction
		(at 125.73 194.31)
		(diameter 0)
		(color 0 0 0 0)
	)
	(junction
		(at 97.79 63.5)
		(diameter 0)
		(color 0 0 0 0)
	)
	(junction
		(at 261.62 53.34)
		(diameter 0)
		(color 0 0 0 0)
	)
	(junction
		(at 207.01 226.06)
		(diameter 0)
		(color 0 0 0 0)
	)
	(junction
		(at 48.26 71.12)
		(diameter 0)
		(color 0 0 0 0)
	)
	(junction
		(at 323.85 194.31)
		(diameter 0)
		(color 0 0 0 0)
	)
	(junction
		(at 274.32 194.31)
		(diameter 0)
		(color 0 0 0 0)
	)
	(junction
		(at 102.87 63.5)
		(diameter 0)
		(color 0 0 0 0)
	)
	(junction
		(at 238.76 63.5)
		(diameter 0)
		(color 0 0 0 0)
	)
	(junction
		(at 287.02 194.31)
		(diameter 0)
		(color 0 0 0 0)
	)
	(junction
		(at 302.26 123.19)
		(diameter 0)
		(color 0 0 0 0)
	)
	(junction
		(at 219.71 53.34)
		(diameter 0)
		(color 0 0 0 0)
	)
	(junction
		(at 157.48 226.06)
		(diameter 0)
		(color 0 0 0 0)
	)
	(junction
		(at 237.49 194.31)
		(diameter 0)
		(color 0 0 0 0)
	)
	(junction
		(at 248.92 124.46)
		(diameter 0)
		(color 0 0 0 0)
	)
	(junction
		(at 295.91 194.31)
		(diameter 0)
		(color 0 0 0 0)
	)
	(junction
		(at 151.13 106.68)
		(diameter 0)
		(color 0 0 0 0)
	)
	(junction
		(at 232.41 86.36)
		(diameter 0)
		(color 0 0 0 0)
	)
	(junction
		(at 143.51 210.82)
		(diameter 0)
		(color 0 0 0 0)
	)
	(junction
		(at 170.18 200.66)
		(diameter 0)
		(color 0 0 0 0)
	)
	(junction
		(at 87.63 63.5)
		(diameter 0)
		(color 0 0 0 0)
	)
	(junction
		(at 304.8 194.31)
		(diameter 0)
		(color 0 0 0 0)
	)
	(junction
		(at 140.97 106.68)
		(diameter 0)
		(color 0 0 0 0)
	)
	(junction
		(at 331.47 194.31)
		(diameter 0)
		(color 0 0 0 0)
	)
	(junction
		(at 269.24 53.34)
		(diameter 0)
		(color 0 0 0 0)
	)
	(junction
		(at 45.72 68.58)
		(diameter 0)
		(color 0 0 0 0)
	)
	(junction
		(at 255.27 194.31)
		(diameter 0)
		(color 0 0 0 0)
	)
	(junction
		(at 269.24 194.31)
		(diameter 0)
		(color 0 0 0 0)
	)
	(junction
		(at 278.13 194.31)
		(diameter 0)
		(color 0 0 0 0)
	)
	(junction
		(at 143.51 194.31)
		(diameter 0)
		(color 0 0 0 0)
	)
	(junction
		(at 250.19 194.31)
		(diameter 0)
		(color 0 0 0 0)
	)
	(junction
		(at 80.01 63.5)
		(diameter 0)
		(color 0 0 0 0)
	)
	(junction
		(at 248.92 53.34)
		(diameter 0)
		(color 0 0 0 0)
	)
	(junction
		(at 285.75 113.03)
		(diameter 0)
		(color 0 0 0 0)
	)
	(junction
		(at 105.41 194.31)
		(diameter 0)
		(color 0 0 0 0)
	)
	(junction
		(at 381 99.06)
		(diameter 0)
		(color 0 0 0 0)
	)
	(junction
		(at 172.72 53.34)
		(diameter 0)
		(color 0 0 0 0)
	)
	(junction
		(at 227.33 63.5)
		(diameter 0)
		(color 0 0 0 0)
	)
	(junction
		(at 227.33 53.34)
		(diameter 0)
		(color 0 0 0 0)
	)
	(junction
		(at 342.9 60.96)
		(diameter 0)
		(color 0 0 0 0)
	)
	(junction
		(at 242.57 213.36)
		(diameter 0)
		(color 0 0 0 0)
	)
	(junction
		(at 106.68 63.5)
		(diameter 0)
		(color 0 0 0 0)
	)
	(junction
		(at 152.4 194.31)
		(diameter 0)
		(color 0 0 0 0)
	)
	(junction
		(at 342.9 99.06)
		(diameter 0)
		(color 0 0 0 0)
	)
	(junction
		(at 242.57 194.31)
		(diameter 0)
		(color 0 0 0 0)
	)
	(junction
		(at 219.71 63.5)
		(diameter 0)
		(color 0 0 0 0)
	)
	(junction
		(at 162.56 194.31)
		(diameter 0)
		(color 0 0 0 0)
	)
	(junction
		(at 41.91 99.06)
		(diameter 0)
		(color 0 0 0 0)
	)
	(junction
		(at 134.62 194.31)
		(diameter 0)
		(color 0 0 0 0)
	)
	(junction
		(at 265.43 53.34)
		(diameter 0)
		(color 0 0 0 0)
	)
	(no_connect
		(at 208.28 76.2)
	)
	(no_connect
		(at 176.53 218.44)
	)
	(no_connect
		(at 175.26 86.36)
	)
	(no_connect
		(at 39.37 88.9)
	)
	(no_connect
		(at 39.37 76.2)
	)
	(no_connect
		(at 175.26 88.9)
	)
	(no_connect
		(at 39.37 83.82)
	)
	(no_connect
		(at 39.37 78.74)
	)
	(no_connect
		(at 204.47 208.28)
	)
	(no_connect
		(at 39.37 81.28)
	)
	(no_connect
		(at 208.28 114.3)
	)
	(no_connect
		(at 204.47 215.9)
	)
	(no_connect
		(at 307.34 72.39)
	)
	(no_connect
		(at 39.37 91.44)
	)
	(no_connect
		(at 208.28 111.76)
	)
	(wire
		(pts
			(xy 97.79 60.96) (xy 97.79 63.5)
		)
		(stroke
			(width 0)
			(type default)
		)
	)
	(wire
		(pts
			(xy 232.41 88.9) (xy 232.41 86.36)
		)
		(stroke
			(width 0)
			(type default)
		)
	)
	(wire
		(pts
			(xy 48.26 71.12) (xy 58.42 71.12)
		)
		(stroke
			(width 0)
			(type default)
		)
	)
	(wire
		(pts
			(xy 116.84 233.68) (xy 116.84 237.49)
		)
		(stroke
			(width 0)
			(type default)
		)
	)
	(wire
		(pts
			(xy 116.84 213.36) (xy 116.84 228.6)
		)
		(stroke
			(width 0)
			(type default)
		)
	)
	(wire
		(pts
			(xy 125.73 233.68) (xy 125.73 237.49)
		)
		(stroke
			(width 0)
			(type default)
		)
	)
	(wire
		(pts
			(xy 255.27 194.31) (xy 262.89 194.31)
		)
		(stroke
			(width 0)
			(type default)
		)
	)
	(wire
		(pts
			(xy 39.37 68.58) (xy 45.72 68.58)
		)
		(stroke
			(width 0)
			(type default)
		)
	)
	(wire
		(pts
			(xy 175.26 114.3) (xy 172.72 114.3)
		)
		(stroke
			(width 0)
			(type default)
		)
	)
	(wire
		(pts
			(xy 287.02 194.31) (xy 287.02 214.63)
		)
		(stroke
			(width 0)
			(type default)
		)
	)
	(wire
		(pts
			(xy 323.85 194.31) (xy 323.85 193.04)
		)
		(stroke
			(width 0)
			(type default)
		)
	)
	(wire
		(pts
			(xy 227.33 63.5) (xy 227.33 60.96)
		)
		(stroke
			(width 0)
			(type default)
		)
	)
	(wire
		(pts
			(xy 370.84 88.9) (xy 381 88.9)
		)
		(stroke
			(width 0)
			(type default)
		)
	)
	(wire
		(pts
			(xy 87.63 63.5) (xy 97.79 63.5)
		)
		(stroke
			(width 0)
			(type default)
		)
	)
	(wire
		(pts
			(xy 295.91 101.6) (xy 285.75 101.6)
		)
		(stroke
			(width 0)
			(type default)
		)
	)
	(wire
		(pts
			(xy 106.68 62.23) (xy 106.68 63.5)
		)
		(stroke
			(width 0)
			(type default)
		)
	)
	(wire
		(pts
			(xy 265.43 53.34) (xy 265.43 81.28)
		)
		(stroke
			(width 0)
			(type default)
		)
	)
	(wire
		(pts
			(xy 262.89 194.31) (xy 269.24 194.31)
		)
		(stroke
			(width 0)
			(type default)
		)
	)
	(wire
		(pts
			(xy 208.28 88.9) (xy 223.52 88.9)
		)
		(stroke
			(width 0)
			(type default)
		)
	)
	(wire
		(pts
			(xy 269.24 52.07) (xy 269.24 53.34)
		)
		(stroke
			(width 0)
			(type default)
		)
	)
	(wire
		(pts
			(xy 133.35 233.68) (xy 133.35 237.49)
		)
		(stroke
			(width 0)
			(type default)
		)
	)
	(wire
		(pts
			(xy 228.6 86.36) (xy 232.41 86.36)
		)
		(stroke
			(width 0)
			(type default)
		)
	)
	(wire
		(pts
			(xy 132.08 106.68) (xy 140.97 106.68)
		)
		(stroke
			(width 0)
			(type default)
		)
	)
	(wire
		(pts
			(xy 261.62 53.34) (xy 265.43 53.34)
		)
		(stroke
			(width 0)
			(type default)
		)
	)
	(wire
		(pts
			(xy 248.92 53.34) (xy 248.92 55.88)
		)
		(stroke
			(width 0)
			(type default)
		)
	)
	(wire
		(pts
			(xy 342.9 68.58) (xy 342.9 71.12)
		)
		(stroke
			(width 0)
			(type default)
		)
	)
	(wire
		(pts
			(xy 250.19 194.31) (xy 255.27 194.31)
		)
		(stroke
			(width 0)
			(type default)
		)
	)
	(wire
		(pts
			(xy 248.92 63.5) (xy 248.92 60.96)
		)
		(stroke
			(width 0)
			(type default)
		)
	)
	(wire
		(pts
			(xy 204.47 203.2) (xy 224.79 203.2)
		)
		(stroke
			(width 0)
			(type default)
		)
	)
	(wire
		(pts
			(xy 303.53 72.39) (xy 303.53 74.93)
		)
		(stroke
			(width 0)
			(type default)
		)
	)
	(wire
		(pts
			(xy 248.92 53.34) (xy 261.62 53.34)
		)
		(stroke
			(width 0)
			(type default)
		)
	)
	(wire
		(pts
			(xy 259.08 88.9) (xy 259.08 115.57)
		)
		(stroke
			(width 0)
			(type default)
		)
	)
	(wire
		(pts
			(xy 227.33 194.31) (xy 227.33 205.74)
		)
		(stroke
			(width 0)
			(type default)
		)
	)
	(wire
		(pts
			(xy 242.57 229.87) (xy 242.57 237.49)
		)
		(stroke
			(width 0)
			(type default)
		)
	)
	(wire
		(pts
			(xy 143.51 194.31) (xy 143.51 196.85)
		)
		(stroke
			(width 0)
			(type default)
		)
	)
	(wire
		(pts
			(xy 157.48 233.68) (xy 157.48 237.49)
		)
		(stroke
			(width 0)
			(type default)
		)
	)
	(wire
		(pts
			(xy 102.87 63.5) (xy 102.87 82.55)
		)
		(stroke
			(width 0)
			(type default)
		)
	)
	(wire
		(pts
			(xy 151.13 106.68) (xy 175.26 106.68)
		)
		(stroke
			(width 0)
			(type default)
		)
	)
	(wire
		(pts
			(xy 39.37 71.12) (xy 48.26 71.12)
		)
		(stroke
			(width 0)
			(type default)
		)
	)
	(wire
		(pts
			(xy 106.68 63.5) (xy 102.87 63.5)
		)
		(stroke
			(width 0)
			(type default)
		)
	)
	(wire
		(pts
			(xy 161.29 78.74) (xy 175.26 78.74)
		)
		(stroke
			(width 0)
			(type default)
		)
	)
	(wire
		(pts
			(xy 381 96.52) (xy 381 99.06)
		)
		(stroke
			(width 0)
			(type default)
		)
	)
	(wire
		(pts
			(xy 219.71 53.34) (xy 172.72 53.34)
		)
		(stroke
			(width 0)
			(type default)
		)
	)
	(wire
		(pts
			(xy 140.97 106.68) (xy 151.13 106.68)
		)
		(stroke
			(width 0)
			(type default)
		)
	)
	(wire
		(pts
			(xy 45.72 68.58) (xy 58.42 68.58)
		)
		(stroke
			(width 0)
			(type default)
		)
	)
	(wire
		(pts
			(xy 242.57 213.36) (xy 242.57 224.79)
		)
		(stroke
			(width 0)
			(type default)
		)
	)
	(wire
		(pts
			(xy 143.51 210.82) (xy 143.51 226.06)
		)
		(stroke
			(width 0)
			(type default)
		)
	)
	(wire
		(pts
			(xy 219.71 60.96) (xy 219.71 63.5)
		)
		(stroke
			(width 0)
			(type default)
		)
	)
	(wire
		(pts
			(xy 342.9 106.68) (xy 342.9 109.22)
		)
		(stroke
			(width 0)
			(type default)
		)
	)
	(wire
		(pts
			(xy 219.71 53.34) (xy 227.33 53.34)
		)
		(stroke
			(width 0)
			(type default)
		)
	)
	(wire
		(pts
			(xy 207.01 223.52) (xy 207.01 226.06)
		)
		(stroke
			(width 0)
			(type default)
		)
	)
	(wire
		(pts
			(xy 242.57 194.31) (xy 242.57 200.66)
		)
		(stroke
			(width 0)
			(type default)
		)
	)
	(wire
		(pts
			(xy 302.26 130.81) (xy 302.26 133.35)
		)
		(stroke
			(width 0)
			(type default)
		)
	)
	(wire
		(pts
			(xy 250.19 218.44) (xy 250.19 237.49)
		)
		(stroke
			(width 0)
			(type default)
		)
	)
	(wire
		(pts
			(xy 105.41 194.31) (xy 115.57 194.31)
		)
		(stroke
			(width 0)
			(type default)
		)
	)
	(wire
		(pts
			(xy 251.46 124.46) (xy 248.92 124.46)
		)
		(stroke
			(width 0)
			(type default)
		)
	)
	(wire
		(pts
			(xy 208.28 86.36) (xy 223.52 86.36)
		)
		(stroke
			(width 0)
			(type default)
		)
	)
	(wire
		(pts
			(xy 172.72 50.8) (xy 172.72 53.34)
		)
		(stroke
			(width 0)
			(type default)
		)
	)
	(wire
		(pts
			(xy 274.32 194.31) (xy 278.13 194.31)
		)
		(stroke
			(width 0)
			(type default)
		)
	)
	(wire
		(pts
			(xy 107.95 210.82) (xy 143.51 210.82)
		)
		(stroke
			(width 0)
			(type default)
		)
	)
	(wire
		(pts
			(xy 299.72 88.9) (xy 299.72 80.01)
		)
		(stroke
			(width 0)
			(type default)
		)
	)
	(wire
		(pts
			(xy 342.9 58.42) (xy 342.9 60.96)
		)
		(stroke
			(width 0)
			(type default)
		)
	)
	(wire
		(pts
			(xy 342.9 99.06) (xy 342.9 101.6)
		)
		(stroke
			(width 0)
			(type default)
		)
	)
	(wire
		(pts
			(xy 304.8 194.31) (xy 314.96 194.31)
		)
		(stroke
			(width 0)
			(type default)
		)
	)
	(wire
		(pts
			(xy 228.6 104.14) (xy 245.11 104.14)
		)
		(stroke
			(width 0)
			(type default)
		)
	)
	(wire
		(pts
			(xy 381 106.68) (xy 381 109.22)
		)
		(stroke
			(width 0)
			(type default)
		)
	)
	(wire
		(pts
			(xy 161.29 109.22) (xy 161.29 111.76)
		)
		(stroke
			(width 0)
			(type default)
		)
	)
	(wire
		(pts
			(xy 143.51 201.93) (xy 143.51 203.2)
		)
		(stroke
			(width 0)
			(type default)
		)
	)
	(wire
		(pts
			(xy 165.1 226.06) (xy 165.1 228.6)
		)
		(stroke
			(width 0)
			(type default)
		)
	)
	(wire
		(pts
			(xy 275.59 101.6) (xy 248.92 101.6)
		)
		(stroke
			(width 0)
			(type default)
		)
	)
	(wire
		(pts
			(xy 295.91 219.71) (xy 295.91 237.49)
		)
		(stroke
			(width 0)
			(type default)
		)
	)
	(wire
		(pts
			(xy 242.57 194.31) (xy 250.19 194.31)
		)
		(stroke
			(width 0)
			(type default)
		)
	)
	(wire
		(pts
			(xy 116.84 213.36) (xy 176.53 213.36)
		)
		(stroke
			(width 0)
			(type default)
		)
	)
	(wire
		(pts
			(xy 48.26 85.09) (xy 50.8 85.09)
		)
		(stroke
			(width 0)
			(type default)
		)
	)
	(wire
		(pts
			(xy 80.01 87.63) (xy 80.01 101.6)
		)
		(stroke
			(width 0)
			(type default)
		)
	)
	(wire
		(pts
			(xy 224.79 200.66) (xy 223.52 200.66)
		)
		(stroke
			(width 0)
			(type default)
		)
	)
	(wire
		(pts
			(xy 320.04 194.31) (xy 323.85 194.31)
		)
		(stroke
			(width 0)
			(type default)
		)
	)
	(wire
		(pts
			(xy 132.08 111.76) (xy 132.08 106.68)
		)
		(stroke
			(width 0)
			(type default)
		)
	)
	(wire
		(pts
			(xy 208.28 104.14) (xy 223.52 104.14)
		)
		(stroke
			(width 0)
			(type default)
		)
	)
	(wire
		(pts
			(xy 204.47 223.52) (xy 207.01 223.52)
		)
		(stroke
			(width 0)
			(type default)
		)
	)
	(wire
		(pts
			(xy 287.02 194.31) (xy 295.91 194.31)
		)
		(stroke
			(width 0)
			(type default)
		)
	)
	(wire
		(pts
			(xy 39.37 96.52) (xy 41.91 96.52)
		)
		(stroke
			(width 0)
			(type default)
		)
	)
	(wire
		(pts
			(xy 48.26 71.12) (xy 48.26 85.09)
		)
		(stroke
			(width 0)
			(type default)
		)
	)
	(wire
		(pts
			(xy 107.95 210.82) (xy 107.95 228.6)
		)
		(stroke
			(width 0)
			(type default)
		)
	)
	(wire
		(pts
			(xy 381 99.06) (xy 396.24 99.06)
		)
		(stroke
			(width 0)
			(type default)
		)
	)
	(wire
		(pts
			(xy 41.91 99.06) (xy 41.91 101.6)
		)
		(stroke
			(width 0)
			(type default)
		)
	)
	(wire
		(pts
			(xy 219.71 63.5) (xy 227.33 63.5)
		)
		(stroke
			(width 0)
			(type default)
		)
	)
	(wire
		(pts
			(xy 161.29 101.6) (xy 175.26 101.6)
		)
		(stroke
			(width 0)
			(type default)
		)
	)
	(wire
		(pts
			(xy 265.43 53.34) (xy 269.24 53.34)
		)
		(stroke
			(width 0)
			(type default)
		)
	)
	(wire
		(pts
			(xy 303.53 50.8) (xy 303.53 53.34)
		)
		(stroke
			(width 0)
			(type default)
		)
	)
	(wire
		(pts
			(xy 242.57 205.74) (xy 242.57 213.36)
		)
		(stroke
			(width 0)
			(type default)
		)
	)
	(wire
		(pts
			(xy 224.79 203.2) (xy 224.79 200.66)
		)
		(stroke
			(width 0)
			(type default)
		)
	)
	(wire
		(pts
			(xy 381 88.9) (xy 381 91.44)
		)
		(stroke
			(width 0)
			(type default)
		)
	)
	(wire
		(pts
			(xy 39.37 63.5) (xy 80.01 63.5)
		)
		(stroke
			(width 0)
			(type default)
		)
	)
	(wire
		(pts
			(xy 246.38 53.34) (xy 248.92 53.34)
		)
		(stroke
			(width 0)
			(type default)
		)
	)
	(wire
		(pts
			(xy 152.4 194.31) (xy 143.51 194.31)
		)
		(stroke
			(width 0)
			(type default)
		)
	)
	(wire
		(pts
			(xy 115.57 194.31) (xy 115.57 196.85)
		)
		(stroke
			(width 0)
			(type default)
		)
	)
	(wire
		(pts
			(xy 99.06 194.31) (xy 105.41 194.31)
		)
		(stroke
			(width 0)
			(type default)
		)
	)
	(wire
		(pts
			(xy 45.72 68.58) (xy 45.72 82.55)
		)
		(stroke
			(width 0)
			(type default)
		)
	)
	(wire
		(pts
			(xy 238.76 63.5) (xy 248.92 63.5)
		)
		(stroke
			(width 0)
			(type default)
		)
	)
	(wire
		(pts
			(xy 157.48 226.06) (xy 157.48 228.6)
		)
		(stroke
			(width 0)
			(type default)
		)
	)
	(wire
		(pts
			(xy 227.33 63.5) (xy 238.76 63.5)
		)
		(stroke
			(width 0)
			(type default)
		)
	)
	(wire
		(pts
			(xy 312.42 114.3) (xy 312.42 88.9)
		)
		(stroke
			(width 0)
			(type default)
		)
	)
	(wire
		(pts
			(xy 161.29 93.98) (xy 175.26 93.98)
		)
		(stroke
			(width 0)
			(type default)
		)
	)
	(wire
		(pts
			(xy 204.47 205.74) (xy 227.33 205.74)
		)
		(stroke
			(width 0)
			(type default)
		)
	)
	(wire
		(pts
			(xy 295.91 194.31) (xy 304.8 194.31)
		)
		(stroke
			(width 0)
			(type default)
		)
	)
	(wire
		(pts
			(xy 162.56 194.31) (xy 170.18 194.31)
		)
		(stroke
			(width 0)
			(type default)
		)
	)
	(wire
		(pts
			(xy 342.9 60.96) (xy 358.14 60.96)
		)
		(stroke
			(width 0)
			(type default)
		)
	)
	(wire
		(pts
			(xy 381 68.58) (xy 381 71.12)
		)
		(stroke
			(width 0)
			(type default)
		)
	)
	(wire
		(pts
			(xy 125.73 215.9) (xy 125.73 228.6)
		)
		(stroke
			(width 0)
			(type default)
		)
	)
	(wire
		(pts
			(xy 381 50.8) (xy 381 53.34)
		)
		(stroke
			(width 0)
			(type default)
		)
	)
	(wire
		(pts
			(xy 278.13 219.71) (xy 278.13 237.49)
		)
		(stroke
			(width 0)
			(type default)
		)
	)
	(wire
		(pts
			(xy 261.62 50.8) (xy 261.62 53.34)
		)
		(stroke
			(width 0)
			(type default)
		)
	)
	(wire
		(pts
			(xy 133.35 220.98) (xy 133.35 228.6)
		)
		(stroke
			(width 0)
			(type default)
		)
	)
	(wire
		(pts
			(xy 323.85 194.31) (xy 331.47 194.31)
		)
		(stroke
			(width 0)
			(type default)
		)
	)
	(wire
		(pts
			(xy 204.47 226.06) (xy 207.01 226.06)
		)
		(stroke
			(width 0)
			(type default)
		)
	)
	(wire
		(pts
			(xy 312.42 133.35) (xy 312.42 127)
		)
		(stroke
			(width 0)
			(type default)
		)
	)
	(wire
		(pts
			(xy 45.72 82.55) (xy 50.8 82.55)
		)
		(stroke
			(width 0)
			(type default)
		)
	)
	(wire
		(pts
			(xy 140.97 116.84) (xy 140.97 119.38)
		)
		(stroke
			(width 0)
			(type default)
		)
	)
	(wire
		(pts
			(xy 285.75 113.03) (xy 302.26 113.03)
		)
		(stroke
			(width 0)
			(type default)
		)
	)
	(wire
		(pts
			(xy 255.27 191.77) (xy 255.27 194.31)
		)
		(stroke
			(width 0)
			(type default)
		)
	)
	(wire
		(pts
			(xy 248.92 124.46) (xy 248.92 101.6)
		)
		(stroke
			(width 0)
			(type default)
		)
	)
	(wire
		(pts
			(xy 151.13 116.84) (xy 151.13 119.38)
		)
		(stroke
			(width 0)
			(type default)
		)
	)
	(wire
		(pts
			(xy 125.73 201.93) (xy 125.73 203.2)
		)
		(stroke
			(width 0)
			(type default)
		)
	)
	(polyline
		(pts
			(xy 124.46 12.7) (xy 124.46 152.4)
		)
		(stroke
			(width 0)
			(type dash)
		)
	)
	(wire
		(pts
			(xy 278.13 124.46) (xy 275.59 124.46)
		)
		(stroke
			(width 0)
			(type default)
		)
	)
	(wire
		(pts
			(xy 274.32 191.77) (xy 274.32 194.31)
		)
		(stroke
			(width 0)
			(type default)
		)
	)
	(wire
		(pts
			(xy 140.97 106.68) (xy 140.97 111.76)
		)
		(stroke
			(width 0)
			(type default)
		)
	)
	(wire
		(pts
			(xy 237.49 210.82) (xy 237.49 194.31)
		)
		(stroke
			(width 0)
			(type default)
		)
	)
	(wire
		(pts
			(xy 143.51 226.06) (xy 146.05 226.06)
		)
		(stroke
			(width 0)
			(type default)
		)
	)
	(wire
		(pts
			(xy 172.72 114.3) (xy 172.72 119.38)
		)
		(stroke
			(width 0)
			(type default)
		)
	)
	(wire
		(pts
			(xy 204.47 210.82) (xy 237.49 210.82)
		)
		(stroke
			(width 0)
			(type default)
		)
	)
	(wire
		(pts
			(xy 161.29 109.22) (xy 175.26 109.22)
		)
		(stroke
			(width 0)
			(type default)
		)
	)
	(wire
		(pts
			(xy 342.9 96.52) (xy 342.9 99.06)
		)
		(stroke
			(width 0)
			(type default)
		)
	)
	(wire
		(pts
			(xy 331.47 191.77) (xy 331.47 194.31)
		)
		(stroke
			(width 0)
			(type default)
		)
	)
	(wire
		(pts
			(xy 172.72 53.34) (xy 172.72 73.66)
		)
		(stroke
			(width 0)
			(type default)
		)
	)
	(wire
		(pts
			(xy 303.53 80.01) (xy 303.53 88.9)
		)
		(stroke
			(width 0)
			(type default)
		)
	)
	(wire
		(pts
			(xy 259.08 88.9) (xy 299.72 88.9)
		)
		(stroke
			(width 0)
			(type default)
		)
	)
	(wire
		(pts
			(xy 125.73 194.31) (xy 134.62 194.31)
		)
		(stroke
			(width 0)
			(type default)
		)
	)
	(wire
		(pts
			(xy 170.18 200.66) (xy 176.53 200.66)
		)
		(stroke
			(width 0)
			(type default)
		)
	)
	(wire
		(pts
			(xy 114.3 60.96) (xy 114.3 63.5)
		)
		(stroke
			(width 0)
			(type default)
		)
	)
	(wire
		(pts
			(xy 332.74 88.9) (xy 342.9 88.9)
		)
		(stroke
			(width 0)
			(type default)
		)
	)
	(wire
		(pts
			(xy 302.26 123.19) (xy 302.26 125.73)
		)
		(stroke
			(width 0)
			(type default)
		)
	)
	(wire
		(pts
			(xy 332.74 50.8) (xy 342.9 50.8)
		)
		(stroke
			(width 0)
			(type default)
		)
	)
	(wire
		(pts
			(xy 134.62 194.31) (xy 134.62 196.85)
		)
		(stroke
			(width 0)
			(type default)
		)
	)
	(wire
		(pts
			(xy 220.98 220.98) (xy 231.14 220.98)
		)
		(stroke
			(width 0)
			(type default)
		)
	)
	(wire
		(pts
			(xy 237.49 194.31) (xy 242.57 194.31)
		)
		(stroke
			(width 0)
			(type default)
		)
	)
	(wire
		(pts
			(xy 161.29 116.84) (xy 161.29 119.38)
		)
		(stroke
			(width 0)
			(type default)
		)
	)
	(wire
		(pts
			(xy 151.13 106.68) (xy 151.13 111.76)
		)
		(stroke
			(width 0)
			(type default)
		)
	)
	(wire
		(pts
			(xy 207.01 226.06) (xy 207.01 237.49)
		)
		(stroke
			(width 0)
			(type default)
		)
	)
	(wire
		(pts
			(xy 162.56 201.93) (xy 162.56 205.74)
		)
		(stroke
			(width 0)
			(type default)
		)
	)
	(wire
		(pts
			(xy 152.4 194.31) (xy 162.56 194.31)
		)
		(stroke
			(width 0)
			(type default)
		)
	)
	(wire
		(pts
			(xy 48.26 101.6) (xy 48.26 87.63)
		)
		(stroke
			(width 0)
			(type default)
		)
	)
	(wire
		(pts
			(xy 285.75 101.6) (xy 285.75 104.14)
		)
		(stroke
			(width 0)
			(type default)
		)
	)
	(wire
		(pts
			(xy 162.56 194.31) (xy 162.56 196.85)
		)
		(stroke
			(width 0)
			(type default)
		)
	)
	(wire
		(pts
			(xy 302.26 123.19) (xy 304.8 123.19)
		)
		(stroke
			(width 0)
			(type default)
		)
	)
	(wire
		(pts
			(xy 228.6 88.9) (xy 232.41 88.9)
		)
		(stroke
			(width 0)
			(type default)
		)
	)
	(wire
		(pts
			(xy 152.4 201.93) (xy 152.4 203.2)
		)
		(stroke
			(width 0)
			(type default)
		)
	)
	(wire
		(pts
			(xy 97.79 63.5) (xy 102.87 63.5)
		)
		(stroke
			(width 0)
			(type default)
		)
	)
	(wire
		(pts
			(xy 342.9 88.9) (xy 342.9 91.44)
		)
		(stroke
			(width 0)
			(type default)
		)
	)
	(wire
		(pts
			(xy 165.1 233.68) (xy 165.1 237.49)
		)
		(stroke
			(width 0)
			(type default)
		)
	)
	(wire
		(pts
			(xy 48.26 87.63) (xy 50.8 87.63)
		)
		(stroke
			(width 0)
			(type default)
		)
	)
	(wire
		(pts
			(xy 41.91 96.52) (xy 41.91 99.06)
		)
		(stroke
			(width 0)
			(type default)
		)
	)
	(wire
		(pts
			(xy 161.29 81.28) (xy 175.26 81.28)
		)
		(stroke
			(width 0)
			(type default)
		)
	)
	(wire
		(pts
			(xy 208.28 73.66) (xy 219.71 73.66)
		)
		(stroke
			(width 0)
			(type default)
		)
	)
	(wire
		(pts
			(xy 269.24 53.34) (xy 276.86 53.34)
		)
		(stroke
			(width 0)
			(type default)
		)
	)
	(polyline
		(pts
			(xy 12.7 152.4) (xy 407.67 152.4)
		)
		(stroke
			(width 0)
			(type dash)
		)
	)
	(wire
		(pts
			(xy 299.72 74.93) (xy 299.72 72.39)
		)
		(stroke
			(width 0)
			(type default)
		)
	)
	(wire
		(pts
			(xy 105.41 194.31) (xy 105.41 196.85)
		)
		(stroke
			(width 0)
			(type default)
		)
	)
	(wire
		(pts
			(xy 114.3 63.5) (xy 106.68 63.5)
		)
		(stroke
			(width 0)
			(type default)
		)
	)
	(wire
		(pts
			(xy 381 60.96) (xy 396.24 60.96)
		)
		(stroke
			(width 0)
			(type default)
		)
	)
	(wire
		(pts
			(xy 39.37 99.06) (xy 41.91 99.06)
		)
		(stroke
			(width 0)
			(type default)
		)
	)
	(wire
		(pts
			(xy 381 60.96) (xy 381 63.5)
		)
		(stroke
			(width 0)
			(type default)
		)
	)
	(wire
		(pts
			(xy 80.01 63.5) (xy 80.01 82.55)
		)
		(stroke
			(width 0)
			(type default)
		)
	)
	(wire
		(pts
			(xy 87.63 60.96) (xy 87.63 63.5)
		)
		(stroke
			(width 0)
			(type default)
		)
	)
	(wire
		(pts
			(xy 269.24 194.31) (xy 269.24 214.63)
		)
		(stroke
			(width 0)
			(type default)
		)
	)
	(wire
		(pts
			(xy 248.92 124.46) (xy 248.92 127)
		)
		(stroke
			(width 0)
			(type default)
		)
	)
	(wire
		(pts
			(xy 381 99.06) (xy 381 101.6)
		)
		(stroke
			(width 0)
			(type default)
		)
	)
	(wire
		(pts
			(xy 134.62 201.93) (xy 134.62 203.2)
		)
		(stroke
			(width 0)
			(type default)
		)
	)
	(wire
		(pts
			(xy 125.73 215.9) (xy 176.53 215.9)
		)
		(stroke
			(width 0)
			(type default)
		)
	)
	(wire
		(pts
			(xy 132.08 116.84) (xy 132.08 119.38)
		)
		(stroke
			(width 0)
			(type default)
		)
	)
	(wire
		(pts
			(xy 170.18 203.2) (xy 170.18 200.66)
		)
		(stroke
			(width 0)
			(type default)
		)
	)
	(wire
		(pts
			(xy 285.75 133.35) (xy 285.75 128.27)
		)
		(stroke
			(width 0)
			(type default)
		)
	)
	(wire
		(pts
			(xy 161.29 99.06) (xy 175.26 99.06)
		)
		(stroke
			(width 0)
			(type default)
		)
	)
	(wire
		(pts
			(xy 250.19 194.31) (xy 250.19 213.36)
		)
		(stroke
			(width 0)
			(type default)
		)
	)
	(wire
		(pts
			(xy 172.72 73.66) (xy 175.26 73.66)
		)
		(stroke
			(width 0)
			(type default)
		)
	)
	(wire
		(pts
			(xy 238.76 59.69) (xy 238.76 63.5)
		)
		(stroke
			(width 0)
			(type default)
		)
	)
	(wire
		(pts
			(xy 342.9 50.8) (xy 342.9 53.34)
		)
		(stroke
			(width 0)
			(type default)
		)
	)
	(wire
		(pts
			(xy 219.71 53.34) (xy 219.71 55.88)
		)
		(stroke
			(width 0)
			(type default)
		)
	)
	(wire
		(pts
			(xy 152.4 194.31) (xy 152.4 196.85)
		)
		(stroke
			(width 0)
			(type default)
		)
	)
	(wire
		(pts
			(xy 115.57 201.93) (xy 115.57 203.2)
		)
		(stroke
			(width 0)
			(type default)
		)
	)
	(wire
		(pts
			(xy 259.08 134.62) (xy 259.08 128.27)
		)
		(stroke
			(width 0)
			(type default)
		)
	)
	(wire
		(pts
			(xy 161.29 96.52) (xy 175.26 96.52)
		)
		(stroke
			(width 0)
			(type default)
		)
	)
	(wire
		(pts
			(xy 278.13 194.31) (xy 287.02 194.31)
		)
		(stroke
			(width 0)
			(type default)
		)
	)
	(wire
		(pts
			(xy 381 58.42) (xy 381 60.96)
		)
		(stroke
			(width 0)
			(type default)
		)
	)
	(wire
		(pts
			(xy 204.47 200.66) (xy 218.44 200.66)
		)
		(stroke
			(width 0)
			(type default)
		)
	)
	(wire
		(pts
			(xy 204.47 220.98) (xy 215.9 220.98)
		)
		(stroke
			(width 0)
			(type default)
		)
	)
	(wire
		(pts
			(xy 227.33 53.34) (xy 227.33 55.88)
		)
		(stroke
			(width 0)
			(type default)
		)
	)
	(wire
		(pts
			(xy 218.44 91.44) (xy 208.28 91.44)
		)
		(stroke
			(width 0)
			(type default)
		)
	)
	(wire
		(pts
			(xy 285.75 113.03) (xy 285.75 115.57)
		)
		(stroke
			(width 0)
			(type default)
		)
	)
	(wire
		(pts
			(xy 134.62 194.31) (xy 143.51 194.31)
		)
		(stroke
			(width 0)
			(type default)
		)
	)
	(wire
		(pts
			(xy 204.47 213.36) (xy 242.57 213.36)
		)
		(stroke
			(width 0)
			(type default)
		)
	)
	(wire
		(pts
			(xy 115.57 194.31) (xy 125.73 194.31)
		)
		(stroke
			(width 0)
			(type default)
		)
	)
	(wire
		(pts
			(xy 162.56 205.74) (xy 176.53 205.74)
		)
		(stroke
			(width 0)
			(type default)
		)
	)
	(wire
		(pts
			(xy 105.41 201.93) (xy 105.41 203.2)
		)
		(stroke
			(width 0)
			(type default)
		)
	)
	(wire
		(pts
			(xy 157.48 223.52) (xy 157.48 226.06)
		)
		(stroke
			(width 0)
			(type default)
		)
	)
	(wire
		(pts
			(xy 232.41 86.36) (xy 242.57 86.36)
		)
		(stroke
			(width 0)
			(type default)
		)
	)
	(wire
		(pts
			(xy 262.89 193.04) (xy 262.89 194.31)
		)
		(stroke
			(width 0)
			(type default)
		)
	)
	(wire
		(pts
			(xy 227.33 194.31) (xy 229.87 194.31)
		)
		(stroke
			(width 0)
			(type default)
		)
	)
	(wire
		(pts
			(xy 208.28 81.28) (xy 265.43 81.28)
		)
		(stroke
			(width 0)
			(type default)
		)
	)
	(wire
		(pts
			(xy 157.48 223.52) (xy 176.53 223.52)
		)
		(stroke
			(width 0)
			(type default)
		)
	)
	(wire
		(pts
			(xy 342.9 60.96) (xy 342.9 63.5)
		)
		(stroke
			(width 0)
			(type default)
		)
	)
	(wire
		(pts
			(xy 285.75 109.22) (xy 285.75 113.03)
		)
		(stroke
			(width 0)
			(type default)
		)
	)
	(wire
		(pts
			(xy 304.8 219.71) (xy 304.8 237.49)
		)
		(stroke
			(width 0)
			(type default)
		)
	)
	(wire
		(pts
			(xy 269.24 219.71) (xy 269.24 237.49)
		)
		(stroke
			(width 0)
			(type default)
		)
	)
	(wire
		(pts
			(xy 269.24 194.31) (xy 274.32 194.31)
		)
		(stroke
			(width 0)
			(type default)
		)
	)
	(wire
		(pts
			(xy 151.13 226.06) (xy 157.48 226.06)
		)
		(stroke
			(width 0)
			(type default)
		)
	)
	(wire
		(pts
			(xy 219.71 71.12) (xy 219.71 73.66)
		)
		(stroke
			(width 0)
			(type default)
		)
	)
	(wire
		(pts
			(xy 248.92 132.08) (xy 248.92 134.62)
		)
		(stroke
			(width 0)
			(type default)
		)
	)
	(wire
		(pts
			(xy 170.18 203.2) (xy 176.53 203.2)
		)
		(stroke
			(width 0)
			(type default)
		)
	)
	(wire
		(pts
			(xy 208.28 101.6) (xy 248.92 101.6)
		)
		(stroke
			(width 0)
			(type default)
		)
	)
	(wire
		(pts
			(xy 304.8 194.31) (xy 304.8 214.63)
		)
		(stroke
			(width 0)
			(type default)
		)
	)
	(wire
		(pts
			(xy 170.18 200.66) (xy 170.18 194.31)
		)
		(stroke
			(width 0)
			(type default)
		)
	)
	(wire
		(pts
			(xy 342.9 99.06) (xy 358.14 99.06)
		)
		(stroke
			(width 0)
			(type default)
		)
	)
	(wire
		(pts
			(xy 278.13 194.31) (xy 278.13 214.63)
		)
		(stroke
			(width 0)
			(type default)
		)
	)
	(wire
		(pts
			(xy 234.95 194.31) (xy 237.49 194.31)
		)
		(stroke
			(width 0)
			(type default)
		)
	)
	(wire
		(pts
			(xy 302.26 113.03) (xy 302.26 123.19)
		)
		(stroke
			(width 0)
			(type default)
		)
	)
	(wire
		(pts
			(xy 80.01 63.5) (xy 87.63 63.5)
		)
		(stroke
			(width 0)
			(type default)
		)
	)
	(wire
		(pts
			(xy 143.51 210.82) (xy 176.53 210.82)
		)
		(stroke
			(width 0)
			(type default)
		)
	)
	(wire
		(pts
			(xy 218.44 96.52) (xy 208.28 96.52)
		)
		(stroke
			(width 0)
			(type default)
		)
	)
	(wire
		(pts
			(xy 102.87 101.6) (xy 102.87 87.63)
		)
		(stroke
			(width 0)
			(type default)
		)
	)
	(wire
		(pts
			(xy 125.73 194.31) (xy 125.73 196.85)
		)
		(stroke
			(width 0)
			(type default)
		)
	)
	(wire
		(pts
			(xy 219.71 63.5) (xy 219.71 66.04)
		)
		(stroke
			(width 0)
			(type default)
		)
	)
	(wire
		(pts
			(xy 295.91 194.31) (xy 295.91 214.63)
		)
		(stroke
			(width 0)
			(type default)
		)
	)
	(wire
		(pts
			(xy 107.95 233.68) (xy 107.95 237.49)
		)
		(stroke
			(width 0)
			(type default)
		)
	)
	(wire
		(pts
			(xy 227.33 53.34) (xy 236.22 53.34)
		)
		(stroke
			(width 0)
			(type default)
		)
	)
	(wire
		(pts
			(xy 275.59 124.46) (xy 275.59 101.6)
		)
		(stroke
			(width 0)
			(type default)
		)
	)
	(wire
		(pts
			(xy 165.1 226.06) (xy 176.53 226.06)
		)
		(stroke
			(width 0)
			(type default)
		)
	)
	(wire
		(pts
			(xy 287.02 219.71) (xy 287.02 237.49)
		)
		(stroke
			(width 0)
			(type default)
		)
	)
	(wire
		(pts
			(xy 370.84 50.8) (xy 381 50.8)
		)
		(stroke
			(width 0)
			(type default)
		)
	)
	(wire
		(pts
			(xy 331.47 194.31) (xy 334.01 194.31)
		)
		(stroke
			(width 0)
			(type default)
		)
	)
	(wire
		(pts
			(xy 133.35 220.98) (xy 176.53 220.98)
		)
		(stroke
			(width 0)
			(type default)
		)
	)
	(wire
		(pts
			(xy 303.53 88.9) (xy 312.42 88.9)
		)
		(stroke
			(width 0)
			(type default)
		)
	)
	(table
		(column_count 2)
		(border
			(external yes)
			(header yes)
			(stroke
				(width 0)
				(type solid)
			)
		)
		(separators
			(rows yes)
			(cols yes)
			(stroke
				(width 0)
				(type solid)
			)
		)
		(column_widths 34.29 35.56)
		(row_heights 3.81 3.81 3.81 3.81)
		(cells
			(table_cell "VBUS_MIN"
				(exclude_from_sim no)
				(at 330.2 30.48 0)
				(size 34.29 3.81)
				(margins 0.9525 0.9525 0.9525 0.9525)
				(span 1 1)
				(fill
					(type none)
				)
				(effects
					(font
						(size 1.27 1.27)
					)
					(justify left top)
				)
			)
			(table_cell "20V"
				(exclude_from_sim no)
				(at 364.49 30.48 0)
				(size 35.56 3.81)
				(margins 0.9525 0.9525 0.9525 0.9525)
				(span 1 1)
				(fill
					(type none)
				)
				(effects
					(font
						(size 1.27 1.27)
					)
					(justify left top)
				)
			)
			(table_cell "VBUS_MAX"
				(exclude_from_sim no)
				(at 330.2 34.29 0)
				(size 34.29 3.81)
				(margins 0.9525 0.9525 0.9525 0.9525)
				(span 1 1)
				(fill
					(type none)
				)
				(effects
					(font
						(size 1.27 1.27)
					)
					(justify left top)
				)
			)
			(table_cell "20V"
				(exclude_from_sim no)
				(at 364.49 34.29 0)
				(size 35.56 3.81)
				(margins 0.9525 0.9525 0.9525 0.9525)
				(span 1 1)
				(fill
					(type none)
				)
				(effects
					(font
						(size 1.27 1.27)
					)
					(justify left top)
				)
			)
			(table_cell "ISNK_FINE"
				(exclude_from_sim no)
				(at 330.2 38.1 0)
				(size 34.29 3.81)
				(margins 0.9525 0.9525 0.9525 0.9525)
				(span 1 1)
				(fill
					(type none)
				)
				(effects
					(font
						(size 1.27 1.27)
					)
					(justify left top)
				)
			)
			(table_cell "0mA"
				(exclude_from_sim no)
				(at 364.49 38.1 0)
				(size 35.56 3.81)
				(margins 0.9525 0.9525 0.9525 0.9525)
				(span 1 1)
				(fill
					(type none)
				)
				(effects
					(font
						(size 1.27 1.27)
					)
					(justify left top)
				)
			)
			(table_cell "ISNK_COARSE"
				(exclude_from_sim no)
				(at 330.2 41.91 0)
				(size 34.29 3.81)
				(margins 0.9525 0.9525 0.9525 0.9525)
				(span 1 1)
				(fill
					(type none)
				)
				(effects
					(font
						(size 1.27 1.27)
					)
					(justify left top)
				)
			)
			(table_cell "5A"
				(exclude_from_sim no)
				(at 364.49 41.91 0)
				(size 35.56 3.81)
				(margins 0.9525 0.9525 0.9525 0.9525)
				(span 1 1)
				(fill
					(type none)
				)
				(effects
					(font
						(size 1.27 1.27)
					)
					(justify left top)
				)
			)
		)
	)
	(table
		(column_count 1)
		(border
			(external yes)
			(header yes)
			(stroke
				(width 0)
				(type solid)
			)
		)
		(separators
			(rows yes)
			(cols yes)
			(stroke
				(width 0)
				(type solid)
			)
		)
		(column_widths 69.85)
		(row_heights 3.81)
		(cells
			(table_cell "CONFIGURATION"
				(exclude_from_sim no)
				(at 330.2 26.67 0)
				(size 69.85 3.81)
				(margins 0.9525 0.9525 0.9525 0.9525)
				(span 1 1)
				(fill
					(type none)
				)
				(effects
					(font
						(size 1.27 1.27)
					)
					(justify left top)
				)
			)
		)
	)
	(label "VDDD_3V3"
		(at 332.74 50.8 0)
		(effects
			(font
				(size 1.27 1.27)
			)
			(justify left bottom)
		)
	)
	(label "12V_SW"
		(at 205.74 205.74 0)
		(effects
			(font
				(size 1.27 1.27)
			)
			(justify left bottom)
		)
	)
	(label "SDA"
		(at 218.44 88.9 180)
		(effects
			(font
				(size 1.27 1.27)
			)
			(justify right bottom)
		)
	)
	(label "FLIP"
		(at 218.44 104.14 180)
		(effects
			(font
				(size 1.27 1.27)
			)
			(justify right bottom)
		)
	)
	(label "12V_VDD"
		(at 165.1 210.82 0)
		(effects
			(font
				(size 1.27 1.27)
			)
			(justify left bottom)
		)
	)
	(label "VDDD_3V3"
		(at 245.11 104.14 180)
		(effects
			(font
				(size 1.27 1.27)
			)
			(justify right bottom)
		)
	)
	(label "CC1"
		(at 161.29 81.28 0)
		(effects
			(font
				(size 1.27 1.27)
			)
			(justify left bottom)
		)
	)
	(label "CC2"
		(at 161.29 78.74 0)
		(effects
			(font
				(size 1.27 1.27)
			)
			(justify left bottom)
		)
	)
	(label "VBUS_MIN"
		(at 161.29 93.98 0)
		(effects
			(font
				(size 1.27 1.27)
			)
			(justify left bottom)
		)
	)
	(label "~{FAULT}"
		(at 302.26 113.03 180)
		(effects
			(font
				(size 1.27 1.27)
			)
			(justify right bottom)
		)
	)
	(label "VDDD_3V3"
		(at 242.57 86.36 180)
		(effects
			(font
				(size 1.27 1.27)
			)
			(justify right bottom)
		)
	)
	(label "VCC"
		(at 276.86 53.34 180)
		(effects
			(font
				(size 1.27 1.27)
			)
			(justify right bottom)
		)
	)
	(label "ISNK_FINE"
		(at 358.14 99.06 180)
		(effects
			(font
				(size 1.27 1.27)
			)
			(justify right bottom)
		)
	)
	(label "12V_ILIM"
		(at 165.1 223.52 0)
		(effects
			(font
				(size 1.27 1.27)
			)
			(justify left bottom)
		)
	)
	(label "12V_VDRV"
		(at 165.1 213.36 0)
		(effects
			(font
				(size 1.27 1.27)
			)
			(justify left bottom)
		)
	)
	(label "GPIO_1"
		(at 218.44 96.52 180)
		(effects
			(font
				(size 1.27 1.27)
			)
			(justify right bottom)
		)
	)
	(label "FAULT"
		(at 218.44 101.6 180)
		(effects
			(font
				(size 1.27 1.27)
			)
			(justify right bottom)
		)
	)
	(label "ISNK_FINE"
		(at 161.29 101.6 0)
		(effects
			(font
				(size 1.27 1.27)
			)
			(justify left bottom)
		)
	)
	(label "VDDD_3V3"
		(at 370.84 50.8 0)
		(effects
			(font
				(size 1.27 1.27)
			)
			(justify left bottom)
		)
	)
	(label "12V_CONV"
		(at 298.45 194.31 0)
		(effects
			(font
				(size 1.27 1.27)
			)
			(justify left bottom)
		)
	)
	(label "VBUS_MIN"
		(at 358.14 60.96 180)
		(effects
			(font
				(size 1.27 1.27)
			)
			(justify right bottom)
		)
	)
	(label "12V_FSW"
		(at 165.1 226.06 0)
		(effects
			(font
				(size 1.27 1.27)
			)
			(justify left bottom)
		)
	)
	(label "12V_EN"
		(at 165.1 205.74 0)
		(effects
			(font
				(size 1.27 1.27)
			)
			(justify left bottom)
		)
	)
	(label "ISNK_COARSE"
		(at 161.29 99.06 0)
		(effects
			(font
				(size 1.27 1.27)
			)
			(justify left bottom)
		)
	)
	(label "VBUS_MAX"
		(at 396.24 60.96 180)
		(effects
			(font
				(size 1.27 1.27)
			)
			(justify right bottom)
		)
	)
	(label "CC1"
		(at 58.42 68.58 180)
		(effects
			(font
				(size 1.27 1.27)
			)
			(justify right bottom)
		)
	)
	(label "12V_MODE"
		(at 165.1 215.9 0)
		(effects
			(font
				(size 1.27 1.27)
			)
			(justify left bottom)
		)
	)
	(label "VDDD_3V3"
		(at 161.29 106.68 0)
		(effects
			(font
				(size 1.27 1.27)
			)
			(justify left bottom)
		)
	)
	(label "12V_VDD"
		(at 231.14 220.98 180)
		(effects
			(font
				(size 1.27 1.27)
			)
			(justify right bottom)
		)
	)
	(label "VDDD_3V3"
		(at 295.91 101.6 180)
		(effects
			(font
				(size 1.27 1.27)
			)
			(justify right bottom)
		)
	)
	(label "VBUS_MAX"
		(at 161.29 96.52 0)
		(effects
			(font
				(size 1.27 1.27)
			)
			(justify left bottom)
		)
	)
	(label "~{HPI_INT}"
		(at 218.44 91.44 180)
		(effects
			(font
				(size 1.27 1.27)
			)
			(justify right bottom)
		)
	)
	(label "ISNK_COARSE"
		(at 396.24 99.06 180)
		(effects
			(font
				(size 1.27 1.27)
			)
			(justify right bottom)
		)
	)
	(label "VDDD_3V3"
		(at 370.84 88.9 0)
		(effects
			(font
				(size 1.27 1.27)
			)
			(justify left bottom)
		)
	)
	(label "VDDD_3V3"
		(at 332.74 88.9 0)
		(effects
			(font
				(size 1.27 1.27)
			)
			(justify left bottom)
		)
	)
	(label "CC2"
		(at 58.42 71.12 180)
		(effects
			(font
				(size 1.27 1.27)
			)
			(justify right bottom)
		)
	)
	(label "12V_BOOT"
		(at 205.74 200.66 0)
		(effects
			(font
				(size 1.27 1.27)
			)
			(justify left bottom)
		)
	)
	(label "VBUS_EN"
		(at 218.44 73.66 180)
		(effects
			(font
				(size 1.27 1.27)
			)
			(justify right bottom)
		)
	)
	(label "SCL"
		(at 218.44 86.36 180)
		(effects
			(font
				(size 1.27 1.27)
			)
			(justify right bottom)
		)
	)
	(label "VCC"
		(at 99.06 194.31 0)
		(effects
			(font
				(size 1.27 1.27)
			)
			(justify left bottom)
		)
	)
	(label "12V_FB"
		(at 205.74 213.36 0)
		(effects
			(font
				(size 1.27 1.27)
			)
			(justify left bottom)
		)
	)
	(label "VCCD_1V8"
		(at 161.29 109.22 0)
		(effects
			(font
				(size 1.27 1.27)
			)
			(justify left bottom)
		)
	)
	(label "12V_SS"
		(at 165.1 220.98 0)
		(effects
			(font
				(size 1.27 1.27)
			)
			(justify left bottom)
		)
	)
	(label "12V_PG"
		(at 205.74 220.98 0)
		(effects
			(font
				(size 1.27 1.27)
			)
			(justify left bottom)
		)
	)
	(hierarchical_label "12V_OUT"
		(shape output)
		(at 334.01 194.31 0)
		(effects
			(font
				(size 1.27 1.27)
			)
			(justify left)
		)
	)
	(netclass_flag ""
		(length 2.54)
		(shape round)
		(at 261.62 50.8 0)
		(effects
			(font
				(size 1.27 1.27)
				(color 255 0 0 1)
			)
			(justify left bottom)
		)
		(property "Netclass" "PWR"
			(at 261.62 46.736 0)
			(effects
				(font
					(size 1.27 1.27)
				)
			)
		)
		(property "Component Class" ""
			(at -111.76 6.35 0)
			(effects
				(font
					(size 1.27 1.27)
					(italic yes)
				)
			)
		)
	)
	(netclass_flag ""
		(length 2.54)
		(shape round)
		(at 255.27 191.77 0)
		(effects
			(font
				(size 1.27 1.27)
				(color 255 0 0 1)
			)
			(justify left bottom)
		)
		(property "Netclass" "PWR"
			(at 255.27 187.706 0)
			(effects
				(font
					(size 1.27 1.27)
				)
			)
		)
		(property "Component Class" ""
			(at -118.11 147.32 0)
			(effects
				(font
					(size 1.27 1.27)
					(italic yes)
				)
			)
		)
	)
	(netclass_flag ""
		(length 2.54)
		(shape round)
		(at 87.63 60.96 0)
		(effects
			(font
				(size 1.27 1.27)
				(color 255 0 0 1)
			)
			(justify left bottom)
		)
		(property "Netclass" "PWR"
			(at 87.63 56.896 0)
			(effects
				(font
					(size 1.27 1.27)
				)
			)
		)
		(property "Component Class" ""
			(at -285.75 16.51 0)
			(effects
				(font
					(size 1.27 1.27)
					(italic yes)
				)
			)
		)
	)
	(netclass_flag ""
		(length 2.54)
		(shape round)
		(at 323.85 193.04 0)
		(fields_autoplaced yes)
		(effects
			(font
				(size 1.27 1.27)
				(color 255 0 0 1)
			)
			(justify left bottom)
		)
		(property "Netclass" "PWR"
			(at 324.5485 190.5 0)
			(effects
				(font
					(size 1.27 1.27)
				)
				(justify left)
			)
		)
		(property "Component Class" ""
			(at -49.53 148.59 0)
			(effects
				(font
					(size 1.27 1.27)
					(italic yes)
				)
			)
		)
	)
	(symbol
		(lib_id "antmicropower:GND")
		(at 269.24 237.49 0)
		(unit 1)
		(exclude_from_sim no)
		(in_bom yes)
		(on_board yes)
		(dnp no)
		(property "Reference" "#PWR041"
			(at 269.24 237.49 0)
			(effects
				(font
					(size 1.27 1.27)
				)
				(justify left)
				(hide yes)
			)
		)
		(property "Value" "GND"
			(at 269.24 241.3 0)
			(effects
				(font
					(size 1.27 1.27)
				)
			)
		)
		(property "Footprint" ""
			(at 269.24 237.49 0)
			(effects
				(font
					(size 1.27 1.27)
					(thickness 0.15)
				)
				(justify left bottom)
				(hide yes)
			)
		)
		(property "Datasheet" ""
			(at 269.24 237.49 0)
			(effects
				(font
					(size 1.27 1.27)
					(thickness 0.15)
				)
				(justify left bottom)
				(hide yes)
			)
		)
		(property "Description" ""
			(at 269.24 237.49 0)
			(effects
				(font
					(size 1.27 1.27)
				)
				(hide yes)
			)
		)
		(property "Author" "Antmicro"
			(at 278.13 245.11 0)
			(effects
				(font
					(size 1.27 1.27)
					(thickness 0.15)
				)
				(justify left bottom)
				(hide yes)
			)
		)
		(property "License" "Apache-2.0"
			(at 278.13 247.65 0)
			(effects
				(font
					(size 1.27 1.27)
					(thickness 0.15)
				)
				(justify left bottom)
				(hide yes)
			)
		)
		(pin "1"
		)
		(instances
			(project "oculink-to-pcie-adapter"
				(path ""
					(reference "#PWR041")
					(unit 1)
				)
			)
		)
	)
	(symbol
		(lib_id "antmicroResistors0402:R_68k_0402")
		(at 157.48 233.68 90)
		(unit 1)
		(exclude_from_sim no)
		(in_bom no)
		(on_board yes)
		(dnp yes)
		(property "Reference" "R31"
			(at 158.75 229.87 90)
			(effects
				(font
					(size 1.27 1.27)
					(thickness 0.15)
				)
				(justify right)
			)
		)
		(property "Value" "R_68k_0402"
			(at 170.18 213.36 0)
			(effects
				(font
					(size 1.27 1.27)
					(thickness 0.15)
				)
				(justify left bottom)
				(hide yes)
			)
		)
		(property "Footprint" "antmicro-footprints:R_0402_1005Metric"
			(at 172.72 213.36 0)
			(effects
				(font
					(size 1.27 1.27)
					(thickness 0.15)
				)
				(justify left bottom)
				(hide yes)
			)
		)
		(property "Datasheet" "https://www.bourns.com/docs/product-datasheets/cr.pdf"
			(at 175.26 213.36 0)
			(effects
				(font
					(size 1.27 1.27)
					(thickness 0.15)
				)
				(justify left bottom)
				(hide yes)
			)
		)
		(property "Description" "SMD Chip Resistor"
			(at 157.48 233.68 0)
			(effects
				(font
					(size 1.27 1.27)
				)
				(hide yes)
			)
		)
		(property "MPN" "CR0402-FX-6802GLF"
			(at 177.8 213.36 0)
			(effects
				(font
					(size 1.27 1.27)
					(thickness 0.15)
				)
				(justify left bottom)
				(hide yes)
			)
		)
		(property "Manufacturer" "Bourns"
			(at 180.34 213.36 0)
			(effects
				(font
					(size 1.27 1.27)
					(thickness 0.15)
				)
				(justify left bottom)
				(hide yes)
			)
		)
		(property "License" "Apache-2.0"
			(at 182.88 213.36 0)
			(effects
				(font
					(size 1.27 1.27)
					(thickness 0.15)
				)
				(justify left bottom)
				(hide yes)
			)
		)
		(property "Author" "Antmicro"
			(at 185.42 213.36 0)
			(effects
				(font
					(size 1.27 1.27)
					(thickness 0.15)
				)
				(justify left bottom)
				(hide yes)
			)
		)
		(property "Val" "68k"
			(at 158.75 232.41 90)
			(effects
				(font
					(size 1.27 1.27)
					(thickness 0.15)
				)
				(justify right)
			)
		)
		(property "Tolerance" "1%"
			(at 167.64 213.36 0)
			(effects
				(font
					(size 1.27 1.27)
				)
				(justify left bottom)
				(hide yes)
			)
		)
		(pin "1"
		)
		(pin "2"
		)
		(instances
			(project "oculink-to-pcie-adapter"
				(path ""
					(reference "R31")
					(unit 1)
				)
			)
		)
	)
	(symbol
		(lib_id "antmicroResistors0402:R_1k_0402")
		(at 342.9 96.52 90)
		(unit 1)
		(exclude_from_sim no)
		(in_bom no)
		(on_board yes)
		(dnp yes)
		(property "Reference" "R24"
			(at 344.17 92.71 90)
			(effects
				(font
					(size 1.27 1.27)
					(thickness 0.15)
				)
				(justify right)
			)
		)
		(property "Value" "R_1k_0402"
			(at 355.6 76.2 0)
			(effects
				(font
					(size 1.27 1.27)
					(thickness 0.15)
				)
				(justify left bottom)
				(hide yes)
			)
		)
		(property "Footprint" "antmicro-footprints:R_0402_1005Metric"
			(at 358.14 76.2 0)
			(effects
				(font
					(size 1.27 1.27)
					(thickness 0.15)
				)
				(justify left bottom)
				(hide yes)
			)
		)
		(property "Datasheet" "https://www.bourns.com/docs/product-datasheets/cr.pdf"
			(at 360.68 76.2 0)
			(effects
				(font
					(size 1.27 1.27)
					(thickness 0.15)
				)
				(justify left bottom)
				(hide yes)
			)
		)
		(property "Description" "SMD Chip Resistor, 1 kohm, ± 1%, 63 mW, 0402 [1005 Metric], Thick Film, General Purpose"
			(at 342.9 96.52 0)
			(effects
				(font
					(size 1.27 1.27)
				)
				(hide yes)
			)
		)
		(property "MPN" "CR0402-FX-1001GLF"
			(at 363.22 76.2 0)
			(effects
				(font
					(size 1.27 1.27)
					(thickness 0.15)
				)
				(justify left bottom)
				(hide yes)
			)
		)
		(property "Manufacturer" "Bourns"
			(at 365.76 76.2 0)
			(effects
				(font
					(size 1.27 1.27)
					(thickness 0.15)
				)
				(justify left bottom)
				(hide yes)
			)
		)
		(property "License" "Apache-2.0"
			(at 368.3 76.2 0)
			(effects
				(font
					(size 1.27 1.27)
					(thickness 0.15)
				)
				(justify left bottom)
				(hide yes)
			)
		)
		(property "Author" "Antmicro"
			(at 370.84 76.2 0)
			(effects
				(font
					(size 1.27 1.27)
					(thickness 0.15)
				)
				(justify left bottom)
				(hide yes)
			)
		)
		(property "Val" "1k"
			(at 344.17 95.25 90)
			(effects
				(font
					(size 1.27 1.27)
					(thickness 0.15)
				)
				(justify right)
			)
		)
		(property "Tolerance" "1%"
			(at 353.06 76.2 0)
			(effects
				(font
					(size 1.27 1.27)
				)
				(justify left bottom)
				(hide yes)
			)
		)
		(pin "2"
		)
		(pin "1"
		)
		(instances
			(project "oculink-to-pcie-adapter"
				(path ""
					(reference "R24")
					(unit 1)
				)
			)
		)
	)
	(symbol
		(lib_id "antmicropower:GND")
		(at 342.9 71.12 0)
		(unit 1)
		(exclude_from_sim no)
		(in_bom yes)
		(on_board yes)
		(dnp no)
		(property "Reference" "#PWR043"
			(at 351.79 73.66 0)
			(effects
				(font
					(size 1.27 1.27)
					(thickness 0.15)
				)
				(justify left bottom)
				(hide yes)
			)
		)
		(property "Value" "GND"
			(at 342.9 74.93 0)
			(effects
				(font
					(size 1.27 1.27)
					(thickness 0.15)
				)
			)
		)
		(property "Footprint" ""
			(at 351.79 78.74 0)
			(effects
				(font
					(size 1.27 1.27)
					(thickness 0.15)
				)
				(justify left bottom)
				(hide yes)
			)
		)
		(property "Datasheet" ""
			(at 351.79 83.82 0)
			(effects
				(font
					(size 1.27 1.27)
					(thickness 0.15)
				)
				(justify left bottom)
				(hide yes)
			)
		)
		(property "Description" ""
			(at 342.9 71.12 0)
			(effects
				(font
					(size 1.27 1.27)
				)
				(hide yes)
			)
		)
		(property "Author" "Antmicro"
			(at 351.79 78.74 0)
			(effects
				(font
					(size 1.27 1.27)
					(thickness 0.15)
				)
				(justify left bottom)
				(hide yes)
			)
		)
		(property "License" "Apache-2.0"
			(at 351.79 81.28 0)
			(effects
				(font
					(size 1.27 1.27)
					(thickness 0.15)
				)
				(justify left bottom)
				(hide yes)
			)
		)
		(pin "1"
		)
		(instances
			(project "oculink-to-pcie-adapter"
				(path ""
					(reference "#PWR043")
					(unit 1)
				)
			)
		)
	)
	(symbol
		(lib_id "antmicropower:PWR_FLAG")
		(at 274.32 191.77 0)
		(unit 1)
		(exclude_from_sim no)
		(in_bom yes)
		(on_board yes)
		(dnp no)
		(property "Reference" "#FLG07"
			(at 274.32 189.865 0)
			(effects
				(font
					(size 1.27 1.27)
				)
				(hide yes)
			)
		)
		(property "Value" "PWR_FLAG"
			(at 274.32 187.96 0)
			(effects
				(font
					(size 1.27 1.27)
				)
			)
		)
		(property "Footprint" ""
			(at 274.32 191.77 0)
			(effects
				(font
					(size 1.27 1.27)
				)
				(hide yes)
			)
		)
		(property "Datasheet" ""
			(at 274.32 191.77 0)
			(effects
				(font
					(size 1.27 1.27)
				)
				(hide yes)
			)
		)
		(property "Description" ""
			(at 274.32 191.77 0)
			(effects
				(font
					(size 1.27 1.27)
				)
				(hide yes)
			)
		)
		(pin "1"
		)
		(instances
			(project "oculink-to-pcie-adapter"
				(path ""
					(reference "#FLG07")
					(unit 1)
				)
			)
		)
	)
	(symbol
		(lib_id "antmicroCapacitors0402:C_1u_25V_0402")
		(at 248.92 60.96 90)
		(unit 1)
		(exclude_from_sim no)
		(in_bom yes)
		(on_board yes)
		(dnp yes)
		(property "Reference" "C38"
			(at 250.952 57.15 90)
			(effects
				(font
					(size 1.27 1.27)
					(thickness 0.15)
				)
				(justify right)
			)
		)
		(property "Value" "C_1u_25V_0402"
			(at 259.08 40.64 0)
			(effects
				(font
					(size 1.27 1.27)
					(thickness 0.15)
				)
				(justify left bottom)
				(hide yes)
			)
		)
		(property "Footprint" "antmicro-footprints:C_0402_1005Metric"
			(at 261.62 40.64 0)
			(effects
				(font
					(size 1.27 1.27)
					(thickness 0.15)
				)
				(justify left bottom)
				(hide yes)
			)
		)
		(property "Datasheet" "https://www.murata.com/products/productdetail?partno=GRM155R61E105KE11%23"
			(at 264.16 40.64 0)
			(effects
				(font
					(size 1.27 1.27)
					(thickness 0.15)
				)
				(justify left bottom)
				(hide yes)
			)
		)
		(property "Description" "SMD Multilayer Ceramic Capacitor, 1 µF, 25 V, 0402 [1005 Metric], ± 10%, X5R, GRM Series"
			(at 248.92 60.96 0)
			(effects
				(font
					(size 1.27 1.27)
				)
				(hide yes)
			)
		)
		(property "MPN" "GRM155R61E105KE11J"
			(at 266.7 40.64 0)
			(effects
				(font
					(size 1.27 1.27)
					(thickness 0.15)
				)
				(justify left bottom)
				(hide yes)
			)
		)
		(property "Manufacturer" "Murata"
			(at 269.24 40.64 0)
			(effects
				(font
					(size 1.27 1.27)
					(thickness 0.15)
				)
				(justify left bottom)
				(hide yes)
			)
		)
		(property "License" "Apache-2.0"
			(at 271.78 40.64 0)
			(effects
				(font
					(size 1.27 1.27)
					(thickness 0.15)
				)
				(justify left bottom)
				(hide yes)
			)
		)
		(property "Author" "Antmicro"
			(at 274.32 40.64 0)
			(effects
				(font
					(size 1.27 1.27)
					(thickness 0.15)
				)
				(justify left bottom)
				(hide yes)
			)
		)
		(property "Val" "1u"
			(at 250.952 59.69 90)
			(effects
				(font
					(size 1.27 1.27)
					(thickness 0.15)
				)
				(justify right)
			)
		)
		(property "Voltage" "25V"
			(at 276.86 40.64 0)
			(effects
				(font
					(size 1.27 1.27)
				)
				(justify left bottom)
				(hide yes)
			)
		)
		(property "Dielectric" "X5R"
			(at 279.4 40.64 0)
			(effects
				(font
					(size 1.27 1.27)
				)
				(justify left bottom)
				(hide yes)
			)
		)
		(pin "1"
		)
		(pin "2"
		)
		(instances
			(project "oculink-to-pcie-adapter"
				(path ""
					(reference "C38")
					(unit 1)
				)
			)
		)
	)
	(symbol
		(lib_id "antmicroTestPoints:TP_Pad0.75mm_Drill0.2mm")
		(at 218.44 96.52 0)
		(unit 1)
		(exclude_from_sim no)
		(in_bom no)
		(on_board yes)
		(dnp no)
		(fields_autoplaced yes)
		(property "Reference" "TP6"
			(at 223.52 96.52 0)
			(effects
				(font
					(size 1.27 1.27)
					(thickness 0.15)
				)
				(justify left)
			)
		)
		(property "Value" "TP_Pad0.75mm_Drill0.2mm"
			(at 228.6 100.33 0)
			(effects
				(font
					(size 1.27 1.27)
					(thickness 0.15)
				)
				(justify left bottom)
				(hide yes)
			)
		)
		(property "Footprint" "antmicro-footprints:TP_Pad0.75mm_Drill0.2mm"
			(at 228.6 102.87 0)
			(effects
				(font
					(size 1.27 1.27)
					(thickness 0.15)
				)
				(justify left bottom)
				(hide yes)
			)
		)
		(property "Datasheet" ""
			(at 236.22 109.22 0)
			(effects
				(font
					(size 1.27 1.27)
					(thickness 0.15)
				)
				(justify left bottom)
				(hide yes)
			)
		)
		(property "Description" "SMT test point"
			(at 218.44 96.52 0)
			(effects
				(font
					(size 1.27 1.27)
				)
				(hide yes)
			)
		)
		(property "MPN" ""
			(at 229.235 107.95 0)
			(effects
				(font
					(size 1.27 1.27)
					(thickness 0.15)
				)
				(justify left bottom)
				(hide yes)
			)
		)
		(property "Manufacturer" ""
			(at 229.235 102.87 0)
			(effects
				(font
					(size 1.27 1.27)
					(thickness 0.15)
				)
				(justify left bottom)
				(hide yes)
			)
		)
		(property "Author" "Antmicro"
			(at 228.6 105.41 0)
			(effects
				(font
					(size 1.27 1.27)
					(thickness 0.15)
				)
				(justify left bottom)
				(hide yes)
			)
		)
		(property "License" "Apache-2.0"
			(at 228.6 107.95 0)
			(effects
				(font
					(size 1.27 1.27)
					(thickness 0.15)
				)
				(justify left bottom)
				(hide yes)
			)
		)
		(pin "1"
		)
		(instances
			(project "oculink-to-pcie-adapter"
				(path ""
					(reference "TP6")
					(unit 1)
				)
			)
		)
	)
	(symbol
		(lib_id "antmicroResistors0402:R_1k_0402")
		(at 342.9 58.42 90)
		(unit 1)
		(exclude_from_sim no)
		(in_bom yes)
		(on_board yes)
		(dnp no)
		(property "Reference" "R29"
			(at 344.17 54.61 90)
			(effects
				(font
					(size 1.27 1.27)
					(thickness 0.15)
				)
				(justify right)
			)
		)
		(property "Value" "R_1k_0402"
			(at 355.6 38.1 0)
			(effects
				(font
					(size 1.27 1.27)
					(thickness 0.15)
				)
				(justify left bottom)
				(hide yes)
			)
		)
		(property "Footprint" "antmicro-footprints:R_0402_1005Metric"
			(at 358.14 38.1 0)
			(effects
				(font
					(size 1.27 1.27)
					(thickness 0.15)
				)
				(justify left bottom)
				(hide yes)
			)
		)
		(property "Datasheet" "https://www.bourns.com/docs/product-datasheets/cr.pdf"
			(at 360.68 38.1 0)
			(effects
				(font
					(size 1.27 1.27)
					(thickness 0.15)
				)
				(justify left bottom)
				(hide yes)
			)
		)
		(property "Description" "SMD Chip Resistor, 1 kohm, ± 1%, 63 mW, 0402 [1005 Metric], Thick Film, General Purpose"
			(at 342.9 58.42 0)
			(effects
				(font
					(size 1.27 1.27)
				)
				(hide yes)
			)
		)
		(property "MPN" "CR0402-FX-1001GLF"
			(at 363.22 38.1 0)
			(effects
				(font
					(size 1.27 1.27)
					(thickness 0.15)
				)
				(justify left bottom)
				(hide yes)
			)
		)
		(property "Manufacturer" "Bourns"
			(at 365.76 38.1 0)
			(effects
				(font
					(size 1.27 1.27)
					(thickness 0.15)
				)
				(justify left bottom)
				(hide yes)
			)
		)
		(property "License" "Apache-2.0"
			(at 368.3 38.1 0)
			(effects
				(font
					(size 1.27 1.27)
					(thickness 0.15)
				)
				(justify left bottom)
				(hide yes)
			)
		)
		(property "Author" "Antmicro"
			(at 370.84 38.1 0)
			(effects
				(font
					(size 1.27 1.27)
					(thickness 0.15)
				)
				(justify left bottom)
				(hide yes)
			)
		)
		(property "Val" "1k"
			(at 344.17 57.15 90)
			(effects
				(font
					(size 1.27 1.27)
					(thickness 0.15)
				)
				(justify right)
			)
		)
		(property "Tolerance" "1%"
			(at 353.06 38.1 0)
			(effects
				(font
					(size 1.27 1.27)
				)
				(justify left bottom)
				(hide yes)
			)
		)
		(pin "2"
		)
		(pin "1"
		)
		(instances
			(project ""
				(path ""
					(reference "R29")
					(unit 1)
				)
			)
		)
	)
	(symbol
		(lib_id "antmicroCapacitorsmisc:C_22u_25V_0805")
		(at 304.8 219.71 90)
		(unit 1)
		(exclude_from_sim no)
		(in_bom yes)
		(on_board yes)
		(dnp no)
		(property "Reference" "C28"
			(at 306.832 214.63 90)
			(effects
				(font
					(size 1.27 1.27)
					(thickness 0.15)
				)
				(justify right)
			)
		)
		(property "Value" "C_22u_25V_0805"
			(at 314.96 199.39 0)
			(effects
				(font
					(size 1.27 1.27)
					(thickness 0.15)
				)
				(justify left bottom)
				(hide yes)
			)
		)
		(property "Footprint" "antmicro-footprints:C_0805_2012Metric"
			(at 317.5 199.39 0)
			(effects
				(font
					(size 1.27 1.27)
					(thickness 0.15)
				)
				(justify left bottom)
				(hide yes)
			)
		)
		(property "Datasheet" "https://product.samsungsem.com/mlcc/CL21A226MAYNNN.do"
			(at 320.04 199.39 0)
			(effects
				(font
					(size 1.27 1.27)
					(thickness 0.15)
				)
				(justify left bottom)
				(hide yes)
			)
		)
		(property "Description" "SMT Multilayer Ceramic Capacitor, 22uF, +/-20%, 25V, X5R, 0805 [2012 Metric]"
			(at 304.8 219.71 0)
			(effects
				(font
					(size 1.27 1.27)
				)
				(hide yes)
			)
		)
		(property "MPN" "CL21A226MAYNNNE"
			(at 322.58 199.39 0)
			(effects
				(font
					(size 1.27 1.27)
					(thickness 0.15)
				)
				(justify left bottom)
				(hide yes)
			)
		)
		(property "Manufacturer" "Samsung Electro-Mechanics"
			(at 325.12 199.39 0)
			(effects
				(font
					(size 1.27 1.27)
					(thickness 0.15)
				)
				(justify left bottom)
				(hide yes)
			)
		)
		(property "License" "Apache-2.0"
			(at 327.66 199.39 0)
			(effects
				(font
					(size 1.27 1.27)
					(thickness 0.15)
				)
				(justify left bottom)
				(hide yes)
			)
		)
		(property "Author" "Antmicro"
			(at 330.2 199.39 0)
			(effects
				(font
					(size 1.27 1.27)
					(thickness 0.15)
				)
				(justify left bottom)
				(hide yes)
			)
		)
		(property "Val" "22u"
			(at 306.832 217.17 90)
			(effects
				(font
					(size 1.27 1.27)
					(thickness 0.15)
				)
				(justify right)
			)
		)
		(property "Voltage" "25V"
			(at 306.832 219.7099 90)
			(effects
				(font
					(size 1.27 1.27)
				)
				(justify right)
			)
		)
		(property "Dielectric" "X5R"
			(at 335.28 199.39 0)
			(effects
				(font
					(size 1.27 1.27)
				)
				(justify left bottom)
				(hide yes)
			)
		)
		(property "Public" "False"
			(at 337.82 199.39 0)
			(effects
				(font
					(size 1.27 1.27)
				)
				(justify left bottom)
				(hide yes)
			)
		)
		(pin "1"
		)
		(pin "2"
		)
		(instances
			(project "oculink-to-pcie-adapter"
				(path ""
					(reference "C28")
					(unit 1)
				)
			)
		)
	)
	(symbol
		(lib_id "antmicroTestPoints:TP_Pad0.75mm_Drill0.2mm")
		(at 262.89 193.04 90)
		(unit 1)
		(exclude_from_sim no)
		(in_bom no)
		(on_board yes)
		(dnp no)
		(property "Reference" "TP13"
			(at 264.16 189.865 90)
			(effects
				(font
					(size 1.27 1.27)
					(thickness 0.15)
				)
				(justify right)
			)
		)
		(property "Value" "TP_Pad0.75mm_Drill0.2mm"
			(at 266.7 182.88 0)
			(effects
				(font
					(size 1.27 1.27)
					(thickness 0.15)
				)
				(justify left bottom)
				(hide yes)
			)
		)
		(property "Footprint" "antmicro-footprints:TP_Pad0.75mm_Drill0.2mm"
			(at 269.24 182.88 0)
			(effects
				(font
					(size 1.27 1.27)
					(thickness 0.15)
				)
				(justify left bottom)
				(hide yes)
			)
		)
		(property "Datasheet" ""
			(at 275.59 175.26 0)
			(effects
				(font
					(size 1.27 1.27)
					(thickness 0.15)
				)
				(justify left bottom)
				(hide yes)
			)
		)
		(property "Description" "SMT test point"
			(at 262.89 193.04 0)
			(effects
				(font
					(size 1.27 1.27)
				)
				(hide yes)
			)
		)
		(property "MPN" ""
			(at 274.32 182.245 0)
			(effects
				(font
					(size 1.27 1.27)
					(thickness 0.15)
				)
				(justify left bottom)
				(hide yes)
			)
		)
		(property "Manufacturer" ""
			(at 269.24 182.245 0)
			(effects
				(font
					(size 1.27 1.27)
					(thickness 0.15)
				)
				(justify left bottom)
				(hide yes)
			)
		)
		(property "Author" "Antmicro"
			(at 271.78 182.88 0)
			(effects
				(font
					(size 1.27 1.27)
					(thickness 0.15)
				)
				(justify left bottom)
				(hide yes)
			)
		)
		(property "License" "Apache-2.0"
			(at 274.32 182.88 0)
			(effects
				(font
					(size 1.27 1.27)
					(thickness 0.15)
				)
				(justify left bottom)
				(hide yes)
			)
		)
		(pin "1"
		)
		(instances
			(project "oculink-to-pcie-adapter"
				(path ""
					(reference "TP13")
					(unit 1)
				)
			)
		)
	)
	(symbol
		(lib_id "antmicroCapacitorsmisc:C_10u_0805_35V")
		(at 143.51 201.93 90)
		(unit 1)
		(exclude_from_sim no)
		(in_bom yes)
		(on_board yes)
		(dnp no)
		(fields_autoplaced yes)
		(property "Reference" "C25"
			(at 146.05 198.1136 90)
			(effects
				(font
					(size 1.27 1.27)
					(thickness 0.15)
				)
				(justify right)
			)
		)
		(property "Value" "C_10u_0805_35V"
			(at 153.67 181.61 0)
			(effects
				(font
					(size 1.27 1.27)
					(thickness 0.15)
				)
				(justify left bottom)
				(hide yes)
			)
		)
		(property "Footprint" "antmicro-footprints:C_0805_2012Metric"
			(at 156.21 181.61 0)
			(effects
				(font
					(size 1.27 1.27)
					(thickness 0.15)
				)
				(justify left bottom)
				(hide yes)
			)
		)
		(property "Datasheet" "https://www.murata.com/products/productdetail?partno=GRM21BR6YA106KE43%23"
			(at 158.75 181.61 0)
			(effects
				(font
					(size 1.27 1.27)
					(thickness 0.15)
				)
				(justify left bottom)
				(hide yes)
			)
		)
		(property "Description" "SMD Multilayer Ceramic Capacitor, 10 µF, 35 V, 0805 [2012 Metric], ± 10%, X5R, GRM Series"
			(at 143.51 201.93 0)
			(effects
				(font
					(size 1.27 1.27)
				)
				(hide yes)
			)
		)
		(property "MPN" "GRM21BR6YA106KE43L"
			(at 161.29 181.61 0)
			(effects
				(font
					(size 1.27 1.27)
					(thickness 0.15)
				)
				(justify left bottom)
				(hide yes)
			)
		)
		(property "Manufacturer" "Murata"
			(at 163.83 181.61 0)
			(effects
				(font
					(size 1.27 1.27)
					(thickness 0.15)
				)
				(justify left bottom)
				(hide yes)
			)
		)
		(property "License" "Apache-2.0"
			(at 166.37 181.61 0)
			(effects
				(font
					(size 1.27 1.27)
					(thickness 0.15)
				)
				(justify left bottom)
				(hide yes)
			)
		)
		(property "Author" "Antmicro"
			(at 168.91 181.61 0)
			(effects
				(font
					(size 1.27 1.27)
					(thickness 0.15)
				)
				(justify left bottom)
				(hide yes)
			)
		)
		(property "Val" "10u"
			(at 146.05 200.6536 90)
			(effects
				(font
					(size 1.27 1.27)
					(thickness 0.15)
				)
				(justify right)
			)
		)
		(property "Voltage" "35V"
			(at 171.45 181.61 0)
			(effects
				(font
					(size 1.27 1.27)
				)
				(justify left bottom)
				(hide yes)
			)
		)
		(property "Dielectric" ""
			(at 173.99 181.61 0)
			(effects
				(font
					(size 1.27 1.27)
				)
				(justify left bottom)
				(hide yes)
			)
		)
		(property "Public" "False"
			(at 176.53 181.61 0)
			(effects
				(font
					(size 1.27 1.27)
				)
				(justify left bottom)
				(hide yes)
			)
		)
		(pin "2"
		)
		(pin "1"
		)
		(instances
			(project "oculink-to-pcie-adapter"
				(path ""
					(reference "C25")
					(unit 1)
				)
			)
		)
	)
	(symbol
		(lib_id "antmicroCapacitors0402:C_100n_0402")
		(at 151.13 116.84 90)
		(unit 1)
		(exclude_from_sim no)
		(in_bom yes)
		(on_board yes)
		(dnp no)
		(fields_autoplaced yes)
		(property "Reference" "C40"
			(at 153.67 113.0236 90)
			(effects
				(font
					(size 1.27 1.27)
					(thickness 0.15)
				)
				(justify right)
			)
		)
		(property "Value" "C_100n_0402"
			(at 161.29 96.52 0)
			(effects
				(font
					(size 1.27 1.27)
					(thickness 0.15)
				)
				(justify left bottom)
				(hide yes)
			)
		)
		(property "Footprint" "antmicro-footprints:C_0402_1005Metric"
			(at 163.83 96.52 0)
			(effects
				(font
					(size 1.27 1.27)
					(thickness 0.15)
				)
				(justify left bottom)
				(hide yes)
			)
		)
		(property "Datasheet" "https://www.murata.com/products/productdetail?partno=GRM155R61H104KE14%23"
			(at 166.37 96.52 0)
			(effects
				(font
					(size 1.27 1.27)
					(thickness 0.15)
				)
				(justify left bottom)
				(hide yes)
			)
		)
		(property "Description" "SMD Multilayer Ceramic Capacitor, 0.1 µF, 50 V, 0402 [1005 Metric], ± 10%, X5R, GRM Series"
			(at 151.13 116.84 0)
			(effects
				(font
					(size 1.27 1.27)
				)
				(hide yes)
			)
		)
		(property "MPN" "GRM155R61H104KE14D"
			(at 168.91 96.52 0)
			(effects
				(font
					(size 1.27 1.27)
					(thickness 0.15)
				)
				(justify left bottom)
				(hide yes)
			)
		)
		(property "Manufacturer" "Murata"
			(at 171.45 96.52 0)
			(effects
				(font
					(size 1.27 1.27)
					(thickness 0.15)
				)
				(justify left bottom)
				(hide yes)
			)
		)
		(property "License" "Apache-2.0"
			(at 173.99 96.52 0)
			(effects
				(font
					(size 1.27 1.27)
					(thickness 0.15)
				)
				(justify left bottom)
				(hide yes)
			)
		)
		(property "Author" "Antmicro"
			(at 176.53 96.52 0)
			(effects
				(font
					(size 1.27 1.27)
					(thickness 0.15)
				)
				(justify left bottom)
				(hide yes)
			)
		)
		(property "Val" "100n"
			(at 153.67 115.5636 90)
			(effects
				(font
					(size 1.27 1.27)
					(thickness 0.15)
				)
				(justify right)
			)
		)
		(property "Voltage" "50V"
			(at 179.07 96.52 0)
			(effects
				(font
					(size 1.27 1.27)
				)
				(justify left bottom)
				(hide yes)
			)
		)
		(property "Dielectric" "X5R"
			(at 181.61 96.52 0)
			(effects
				(font
					(size 1.27 1.27)
				)
				(justify left bottom)
				(hide yes)
			)
		)
		(pin "1"
		)
		(pin "2"
		)
		(instances
			(project "oculink-to-pcie-adapter"
				(path ""
					(reference "C40")
					(unit 1)
				)
			)
		)
	)
	(symbol
		(lib_id "antmicropower:GND")
		(at 304.8 237.49 0)
		(unit 1)
		(exclude_from_sim no)
		(in_bom yes)
		(on_board yes)
		(dnp no)
		(property "Reference" "#PWR066"
			(at 304.8 237.49 0)
			(effects
				(font
					(size 1.27 1.27)
				)
				(justify left)
				(hide yes)
			)
		)
		(property "Value" "GND"
			(at 304.8 241.3 0)
			(effects
				(font
					(size 1.27 1.27)
				)
			)
		)
		(property "Footprint" ""
			(at 304.8 237.49 0)
			(effects
				(font
					(size 1.27 1.27)
					(thickness 0.15)
				)
				(justify left bottom)
				(hide yes)
			)
		)
		(property "Datasheet" ""
			(at 304.8 237.49 0)
			(effects
				(font
					(size 1.27 1.27)
					(thickness 0.15)
				)
				(justify left bottom)
				(hide yes)
			)
		)
		(property "Description" ""
			(at 304.8 237.49 0)
			(effects
				(font
					(size 1.27 1.27)
				)
				(hide yes)
			)
		)
		(property "Author" "Antmicro"
			(at 313.69 245.11 0)
			(effects
				(font
					(size 1.27 1.27)
					(thickness 0.15)
				)
				(justify left bottom)
				(hide yes)
			)
		)
		(property "License" "Apache-2.0"
			(at 313.69 247.65 0)
			(effects
				(font
					(size 1.27 1.27)
					(thickness 0.15)
				)
				(justify left bottom)
				(hide yes)
			)
		)
		(pin "1"
		)
		(instances
			(project "oculink-to-pcie-adapter"
				(path ""
					(reference "#PWR066")
					(unit 1)
				)
			)
		)
	)
	(symbol
		(lib_id "antmicroResistors0402:R_10k_0402")
		(at 299.72 80.01 270)
		(mirror x)
		(unit 1)
		(exclude_from_sim no)
		(in_bom yes)
		(on_board yes)
		(dnp no)
		(property "Reference" "R36"
			(at 298.45 76.454 90)
			(effects
				(font
					(size 1.27 1.27)
					(thickness 0.15)
				)
				(justify right)
			)
		)
		(property "Value" "R_10k_0402"
			(at 287.02 59.69 0)
			(effects
				(font
					(size 1.27 1.27)
					(thickness 0.15)
				)
				(justify left bottom)
				(hide yes)
			)
		)
		(property "Footprint" "antmicro-footprints:R_0402_1005Metric"
			(at 284.48 59.69 0)
			(effects
				(font
					(size 1.27 1.27)
					(thickness 0.15)
				)
				(justify left bottom)
				(hide yes)
			)
		)
		(property "Datasheet" "https://www.bourns.com/docs/product-datasheets/cr.pdf"
			(at 281.94 59.69 0)
			(effects
				(font
					(size 1.27 1.27)
					(thickness 0.15)
				)
				(justify left bottom)
				(hide yes)
			)
		)
		(property "Description" "SMD Chip Resistor, 10 kohm, ± 1%, 62.5 mW, 0402 [1005 Metric], Thick Film, General Purpose"
			(at 299.72 80.01 0)
			(effects
				(font
					(size 1.27 1.27)
				)
				(hide yes)
			)
		)
		(property "MPN" "CR0402-FX-1002GLF"
			(at 279.4 59.69 0)
			(effects
				(font
					(size 1.27 1.27)
					(thickness 0.15)
				)
				(justify left bottom)
				(hide yes)
			)
		)
		(property "Manufacturer" "Bourns"
			(at 276.86 59.69 0)
			(effects
				(font
					(size 1.27 1.27)
					(thickness 0.15)
				)
				(justify left bottom)
				(hide yes)
			)
		)
		(property "License" "Apache-2.0"
			(at 274.32 59.69 0)
			(effects
				(font
					(size 1.27 1.27)
					(thickness 0.15)
				)
				(justify left bottom)
				(hide yes)
			)
		)
		(property "Author" "Antmicro"
			(at 271.78 59.69 0)
			(effects
				(font
					(size 1.27 1.27)
					(thickness 0.15)
				)
				(justify left bottom)
				(hide yes)
			)
		)
		(property "Val" "10k"
			(at 298.45 78.994 90)
			(effects
				(font
					(size 1.27 1.27)
					(thickness 0.15)
				)
				(justify right)
			)
		)
		(property "Tolerance" "1%"
			(at 289.56 59.69 0)
			(effects
				(font
					(size 1.27 1.27)
				)
				(justify left bottom)
				(hide yes)
			)
		)
		(pin "2"
		)
		(pin "1"
		)
		(instances
			(project "oculink-to-pcie-adapter"
				(path ""
					(reference "R36")
					(unit 1)
				)
			)
		)
	)
	(symbol
		(lib_id "antmicroResistors0402:R_158k_0402")
		(at 165.1 233.68 90)
		(unit 1)
		(exclude_from_sim no)
		(in_bom yes)
		(on_board yes)
		(dnp no)
		(property "Reference" "R33"
			(at 166.37 229.87 90)
			(effects
				(font
					(size 1.27 1.27)
					(thickness 0.15)
				)
				(justify right)
			)
		)
		(property "Value" "R_158k_0402"
			(at 177.8 213.36 0)
			(effects
				(font
					(size 1.27 1.27)
					(thickness 0.15)
				)
				(justify left bottom)
				(hide yes)
			)
		)
		(property "Footprint" "antmicro-footprints:R_0402_1005Metric"
			(at 180.34 213.36 0)
			(effects
				(font
					(size 1.27 1.27)
					(thickness 0.15)
				)
				(justify left bottom)
				(hide yes)
			)
		)
		(property "Datasheet" "https://www.bourns.com/docs/product-datasheets/cr.pdf"
			(at 182.88 213.36 0)
			(effects
				(font
					(size 1.27 1.27)
					(thickness 0.15)
				)
				(justify left bottom)
				(hide yes)
			)
		)
		(property "Description" "SMD Chip Resistor, 158 kohm, ± 1%, 100 mW, 0402 [1005 Metric], Thick Film, Precision"
			(at 165.1 233.68 0)
			(effects
				(font
					(size 1.27 1.27)
				)
				(hide yes)
			)
		)
		(property "MPN" "CR0402-FX-1583GLF"
			(at 185.42 213.36 0)
			(effects
				(font
					(size 1.27 1.27)
					(thickness 0.15)
				)
				(justify left bottom)
				(hide yes)
			)
		)
		(property "Manufacturer" "Bourns"
			(at 187.96 213.36 0)
			(effects
				(font
					(size 1.27 1.27)
					(thickness 0.15)
				)
				(justify left bottom)
				(hide yes)
			)
		)
		(property "License" "Apache-2.0"
			(at 190.5 213.36 0)
			(effects
				(font
					(size 1.27 1.27)
					(thickness 0.15)
				)
				(justify left bottom)
				(hide yes)
			)
		)
		(property "Author" "Antmicro"
			(at 193.04 213.36 0)
			(effects
				(font
					(size 1.27 1.27)
					(thickness 0.15)
				)
				(justify left bottom)
				(hide yes)
			)
		)
		(property "Val" "158k"
			(at 166.37 232.41 90)
			(effects
				(font
					(size 1.27 1.27)
					(thickness 0.15)
				)
				(justify right)
			)
		)
		(property "Tolerance" "1%"
			(at 175.26 213.36 0)
			(effects
				(font
					(size 1.27 1.27)
				)
				(justify left bottom)
				(hide yes)
			)
		)
		(pin "1"
		)
		(pin "2"
		)
		(instances
			(project "oculink-to-pcie-adapter"
				(path ""
					(reference "R33")
					(unit 1)
				)
			)
		)
	)
	(symbol
		(lib_id "antmicroResistors0402:R_100k_0402")
		(at 162.56 201.93 90)
		(unit 1)
		(exclude_from_sim no)
		(in_bom yes)
		(on_board yes)
		(dnp no)
		(property "Reference" "R32"
			(at 164.084 198.1199 90)
			(effects
				(font
					(size 1.27 1.27)
				)
				(justify right)
			)
		)
		(property "Value" "R_100k_0402"
			(at 166.37 201.93 0)
			(effects
				(font
					(size 1.27 1.27)
				)
				(justify left)
				(hide yes)
			)
		)
		(property "Footprint" "antmicro-footprints:R_0402_1005Metric"
			(at 157.48 196.85 0)
			(effects
				(font
					(size 1.27 1.27)
					(thickness 0.15)
				)
				(justify left bottom)
				(hide yes)
			)
		)
		(property "Datasheet" "https://www.bourns.com/docs/product-datasheets/cr.pdf"
			(at 162.56 201.93 0)
			(effects
				(font
					(size 1.27 1.27)
					(thickness 0.15)
				)
				(justify left bottom)
				(hide yes)
			)
		)
		(property "Description" "SMD Chip Resistor, 100 kohm, ± 1%, 62.5 mW, 0402 [1005 Metric], Thick Film, General Purpose"
			(at 162.56 201.93 0)
			(effects
				(font
					(size 1.27 1.27)
				)
				(hide yes)
			)
		)
		(property "Manufacturer" "Bourns"
			(at 152.4 196.85 0)
			(effects
				(font
					(size 1.27 1.27)
					(thickness 0.15)
				)
				(justify left bottom)
				(hide yes)
			)
		)
		(property "MPN" "CR0402-FX-1003GLF"
			(at 154.94 196.85 0)
			(effects
				(font
					(size 1.27 1.27)
					(thickness 0.15)
				)
				(justify left bottom)
				(hide yes)
			)
		)
		(property "Val" "100k"
			(at 164.084 200.66 90)
			(effects
				(font
					(size 1.27 1.27)
					(thickness 0.15)
				)
				(justify right)
			)
		)
		(property "License" "Apache-2.0"
			(at 187.96 181.61 0)
			(effects
				(font
					(size 1.27 1.27)
					(thickness 0.15)
				)
				(justify left bottom)
				(hide yes)
			)
		)
		(property "Author" "Antmicro"
			(at 190.5 181.61 0)
			(effects
				(font
					(size 1.27 1.27)
					(thickness 0.15)
				)
				(justify left bottom)
				(hide yes)
			)
		)
		(property "Tolerance" "1%"
			(at 172.72 181.61 0)
			(effects
				(font
					(size 1.27 1.27)
				)
				(justify left bottom)
				(hide yes)
			)
		)
		(pin "1"
		)
		(pin "2"
		)
		(instances
			(project "oculink-to-pcie-adapter"
				(path ""
					(reference "R32")
					(unit 1)
				)
			)
		)
	)
	(symbol
		(lib_id "antmicropower:GND")
		(at 157.48 237.49 0)
		(unit 1)
		(exclude_from_sim no)
		(in_bom yes)
		(on_board yes)
		(dnp no)
		(property "Reference" "#PWR073"
			(at 157.48 237.49 0)
			(effects
				(font
					(size 1.27 1.27)
				)
				(justify left)
				(hide yes)
			)
		)
		(property "Value" "GND"
			(at 157.48 241.3 0)
			(effects
				(font
					(size 1.27 1.27)
				)
			)
		)
		(property "Footprint" ""
			(at 157.48 237.49 0)
			(effects
				(font
					(size 1.27 1.27)
					(thickness 0.15)
				)
				(justify left bottom)
				(hide yes)
			)
		)
		(property "Datasheet" ""
			(at 157.48 237.49 0)
			(effects
				(font
					(size 1.27 1.27)
					(thickness 0.15)
				)
				(justify left bottom)
				(hide yes)
			)
		)
		(property "Description" ""
			(at 157.48 237.49 0)
			(effects
				(font
					(size 1.27 1.27)
				)
				(hide yes)
			)
		)
		(property "Author" "Antmicro"
			(at 166.37 245.11 0)
			(effects
				(font
					(size 1.27 1.27)
					(thickness 0.15)
				)
				(justify left bottom)
				(hide yes)
			)
		)
		(property "License" "Apache-2.0"
			(at 166.37 247.65 0)
			(effects
				(font
					(size 1.27 1.27)
					(thickness 0.15)
				)
				(justify left bottom)
				(hide yes)
			)
		)
		(pin "1"
		)
		(instances
			(project "oculink-to-pcie-adapter"
				(path ""
					(reference "#PWR073")
					(unit 1)
				)
			)
		)
	)
	(symbol
		(lib_id "antmicroResistors0402:R_1k_0402")
		(at 285.75 109.22 90)
		(unit 1)
		(exclude_from_sim no)
		(in_bom yes)
		(on_board yes)
		(dnp no)
		(property "Reference" "R48"
			(at 287.02 105.41 90)
			(effects
				(font
					(size 1.27 1.27)
					(thickness 0.15)
				)
				(justify right)
			)
		)
		(property "Value" "R_1k_0402"
			(at 298.45 88.9 0)
			(effects
				(font
					(size 1.27 1.27)
					(thickness 0.15)
				)
				(justify left bottom)
				(hide yes)
			)
		)
		(property "Footprint" "antmicro-footprints:R_0402_1005Metric"
			(at 300.99 88.9 0)
			(effects
				(font
					(size 1.27 1.27)
					(thickness 0.15)
				)
				(justify left bottom)
				(hide yes)
			)
		)
		(property "Datasheet" "https://www.bourns.com/docs/product-datasheets/cr.pdf"
			(at 303.53 88.9 0)
			(effects
				(font
					(size 1.27 1.27)
					(thickness 0.15)
				)
				(justify left bottom)
				(hide yes)
			)
		)
		(property "Description" "SMD Chip Resistor, 1 kohm, ± 1%, 63 mW, 0402 [1005 Metric], Thick Film, General Purpose"
			(at 285.75 109.22 0)
			(effects
				(font
					(size 1.27 1.27)
				)
				(hide yes)
			)
		)
		(property "MPN" "CR0402-FX-1001GLF"
			(at 306.07 88.9 0)
			(effects
				(font
					(size 1.27 1.27)
					(thickness 0.15)
				)
				(justify left bottom)
				(hide yes)
			)
		)
		(property "Manufacturer" "Bourns"
			(at 308.61 88.9 0)
			(effects
				(font
					(size 1.27 1.27)
					(thickness 0.15)
				)
				(justify left bottom)
				(hide yes)
			)
		)
		(property "License" "Apache-2.0"
			(at 311.15 88.9 0)
			(effects
				(font
					(size 1.27 1.27)
					(thickness 0.15)
				)
				(justify left bottom)
				(hide yes)
			)
		)
		(property "Author" "Antmicro"
			(at 313.69 88.9 0)
			(effects
				(font
					(size 1.27 1.27)
					(thickness 0.15)
				)
				(justify left bottom)
				(hide yes)
			)
		)
		(property "Val" "1k"
			(at 287.02 107.95 90)
			(effects
				(font
					(size 1.27 1.27)
					(thickness 0.15)
				)
				(justify right)
			)
		)
		(property "Tolerance" "1%"
			(at 295.91 88.9 0)
			(effects
				(font
					(size 1.27 1.27)
				)
				(justify left bottom)
				(hide yes)
			)
		)
		(pin "2"
		)
		(pin "1"
		)
		(instances
			(project "oculink-to-pcie-adapter"
				(path ""
					(reference "R48")
					(unit 1)
				)
			)
		)
	)
	(symbol
		(lib_id "antmicropower:GND")
		(at 207.01 237.49 0)
		(unit 1)
		(exclude_from_sim no)
		(in_bom yes)
		(on_board yes)
		(dnp no)
		(property "Reference" "#PWR075"
			(at 207.01 237.49 0)
			(effects
				(font
					(size 1.27 1.27)
				)
				(justify left)
				(hide yes)
			)
		)
		(property "Value" "GND"
			(at 207.01 241.3 0)
			(effects
				(font
					(size 1.27 1.27)
				)
			)
		)
		(property "Footprint" ""
			(at 207.01 237.49 0)
			(effects
				(font
					(size 1.27 1.27)
					(thickness 0.15)
				)
				(justify left bottom)
				(hide yes)
			)
		)
		(property "Datasheet" ""
			(at 207.01 237.49 0)
			(effects
				(font
					(size 1.27 1.27)
					(thickness 0.15)
				)
				(justify left bottom)
				(hide yes)
			)
		)
		(property "Description" ""
			(at 207.01 237.49 0)
			(effects
				(font
					(size 1.27 1.27)
				)
				(hide yes)
			)
		)
		(property "Author" "Antmicro"
			(at 215.9 245.11 0)
			(effects
				(font
					(size 1.27 1.27)
					(thickness 0.15)
				)
				(justify left bottom)
				(hide yes)
			)
		)
		(property "License" "Apache-2.0"
			(at 215.9 247.65 0)
			(effects
				(font
					(size 1.27 1.27)
					(thickness 0.15)
				)
				(justify left bottom)
				(hide yes)
			)
		)
		(pin "1"
		)
		(instances
			(project "oculink-to-pcie-adapter"
				(path ""
					(reference "#PWR075")
					(unit 1)
				)
			)
		)
	)
	(symbol
		(lib_id "antmicroResistors0402:R_10k_0402")
		(at 219.71 60.96 90)
		(unit 1)
		(exclude_from_sim no)
		(in_bom yes)
		(on_board yes)
		(dnp no)
		(property "Reference" "R27"
			(at 220.98 57.404 90)
			(effects
				(font
					(size 1.27 1.27)
					(thickness 0.15)
				)
				(justify right)
			)
		)
		(property "Value" "R_10k_0402"
			(at 232.41 40.64 0)
			(effects
				(font
					(size 1.27 1.27)
					(thickness 0.15)
				)
				(justify left bottom)
				(hide yes)
			)
		)
		(property "Footprint" "antmicro-footprints:R_0402_1005Metric"
			(at 234.95 40.64 0)
			(effects
				(font
					(size 1.27 1.27)
					(thickness 0.15)
				)
				(justify left bottom)
				(hide yes)
			)
		)
		(property "Datasheet" "https://www.bourns.com/docs/product-datasheets/cr.pdf"
			(at 237.49 40.64 0)
			(effects
				(font
					(size 1.27 1.27)
					(thickness 0.15)
				)
				(justify left bottom)
				(hide yes)
			)
		)
		(property "Description" "SMD Chip Resistor, 10 kohm, ± 1%, 62.5 mW, 0402 [1005 Metric], Thick Film, General Purpose"
			(at 219.71 60.96 0)
			(effects
				(font
					(size 1.27 1.27)
				)
				(hide yes)
			)
		)
		(property "MPN" "CR0402-FX-1002GLF"
			(at 240.03 40.64 0)
			(effects
				(font
					(size 1.27 1.27)
					(thickness 0.15)
				)
				(justify left bottom)
				(hide yes)
			)
		)
		(property "Manufacturer" "Bourns"
			(at 242.57 40.64 0)
			(effects
				(font
					(size 1.27 1.27)
					(thickness 0.15)
				)
				(justify left bottom)
				(hide yes)
			)
		)
		(property "License" "Apache-2.0"
			(at 245.11 40.64 0)
			(effects
				(font
					(size 1.27 1.27)
					(thickness 0.15)
				)
				(justify left bottom)
				(hide yes)
			)
		)
		(property "Author" "Antmicro"
			(at 247.65 40.64 0)
			(effects
				(font
					(size 1.27 1.27)
					(thickness 0.15)
				)
				(justify left bottom)
				(hide yes)
			)
		)
		(property "Val" "10k"
			(at 220.98 59.944 90)
			(effects
				(font
					(size 1.27 1.27)
					(thickness 0.15)
				)
				(justify right)
			)
		)
		(property "Tolerance" "1%"
			(at 229.87 40.64 0)
			(effects
				(font
					(size 1.27 1.27)
				)
				(justify left bottom)
				(hide yes)
			)
		)
		(pin "2"
		)
		(pin "1"
		)
		(instances
			(project "oculink-to-pcie-adapter"
				(path ""
					(reference "R27")
					(unit 1)
				)
			)
		)
	)
	(symbol
		(lib_id "antmicropower:GND")
		(at 132.08 119.38 0)
		(unit 1)
		(exclude_from_sim no)
		(in_bom yes)
		(on_board yes)
		(dnp no)
		(property "Reference" "#PWR0101"
			(at 140.97 121.92 0)
			(effects
				(font
					(size 1.27 1.27)
					(thickness 0.15)
				)
				(justify left bottom)
				(hide yes)
			)
		)
		(property "Value" "GND"
			(at 132.08 123.19 0)
			(effects
				(font
					(size 1.27 1.27)
					(thickness 0.15)
				)
			)
		)
		(property "Footprint" ""
			(at 140.97 127 0)
			(effects
				(font
					(size 1.27 1.27)
					(thickness 0.15)
				)
				(justify left bottom)
				(hide yes)
			)
		)
		(property "Datasheet" ""
			(at 140.97 132.08 0)
			(effects
				(font
					(size 1.27 1.27)
					(thickness 0.15)
				)
				(justify left bottom)
				(hide yes)
			)
		)
		(property "Description" ""
			(at 132.08 119.38 0)
			(effects
				(font
					(size 1.27 1.27)
				)
				(hide yes)
			)
		)
		(property "Author" "Antmicro"
			(at 140.97 127 0)
			(effects
				(font
					(size 1.27 1.27)
					(thickness 0.15)
				)
				(justify left bottom)
				(hide yes)
			)
		)
		(property "License" "Apache-2.0"
			(at 140.97 129.54 0)
			(effects
				(font
					(size 1.27 1.27)
					(thickness 0.15)
				)
				(justify left bottom)
				(hide yes)
			)
		)
		(pin "1"
		)
		(instances
			(project "oculink-to-pcie-adapter"
				(path ""
					(reference "#PWR0101")
					(unit 1)
				)
			)
		)
	)
	(symbol
		(lib_id "antmicroCapacitors0402:C_100n_0402")
		(at 218.44 200.66 0)
		(unit 1)
		(exclude_from_sim no)
		(in_bom yes)
		(on_board yes)
		(dnp no)
		(property "Reference" "C27"
			(at 218.186 199.39 0)
			(effects
				(font
					(size 1.27 1.27)
					(thickness 0.15)
				)
			)
		)
		(property "Value" "C_100n_0402"
			(at 238.76 210.82 0)
			(effects
				(font
					(size 1.27 1.27)
					(thickness 0.15)
				)
				(justify left bottom)
				(hide yes)
			)
		)
		(property "Footprint" "antmicro-footprints:C_0402_1005Metric"
			(at 238.76 213.36 0)
			(effects
				(font
					(size 1.27 1.27)
					(thickness 0.15)
				)
				(justify left bottom)
				(hide yes)
			)
		)
		(property "Datasheet" "https://www.murata.com/products/productdetail?partno=GRM155R61H104KE14%23"
			(at 238.76 215.9 0)
			(effects
				(font
					(size 1.27 1.27)
					(thickness 0.15)
				)
				(justify left bottom)
				(hide yes)
			)
		)
		(property "Description" "SMD Multilayer Ceramic Capacitor, 0.1 µF, 50 V, 0402 [1005 Metric], ± 10%, X5R, GRM Series"
			(at 218.44 200.66 0)
			(effects
				(font
					(size 1.27 1.27)
				)
				(hide yes)
			)
		)
		(property "MPN" "GRM155R61H104KE14D"
			(at 238.76 218.44 0)
			(effects
				(font
					(size 1.27 1.27)
					(thickness 0.15)
				)
				(justify left bottom)
				(hide yes)
			)
		)
		(property "Manufacturer" "Murata"
			(at 238.76 220.98 0)
			(effects
				(font
					(size 1.27 1.27)
					(thickness 0.15)
				)
				(justify left bottom)
				(hide yes)
			)
		)
		(property "License" "Apache-2.0"
			(at 238.76 223.52 0)
			(effects
				(font
					(size 1.27 1.27)
					(thickness 0.15)
				)
				(justify left bottom)
				(hide yes)
			)
		)
		(property "Author" "Antmicro"
			(at 238.76 226.06 0)
			(effects
				(font
					(size 1.27 1.27)
					(thickness 0.15)
				)
				(justify left bottom)
				(hide yes)
			)
		)
		(property "Val" "100n"
			(at 224.282 199.39 0)
			(effects
				(font
					(size 1.27 1.27)
					(thickness 0.15)
				)
			)
		)
		(property "Voltage" "50V"
			(at 238.76 228.6 0)
			(effects
				(font
					(size 1.27 1.27)
				)
				(justify left bottom)
				(hide yes)
			)
		)
		(property "Dielectric" "X5R"
			(at 238.76 231.14 0)
			(effects
				(font
					(size 1.27 1.27)
				)
				(justify left bottom)
				(hide yes)
			)
		)
		(pin "1"
		)
		(pin "2"
		)
		(instances
			(project "oculink-to-pcie-adapter"
				(path ""
					(reference "C27")
					(unit 1)
				)
			)
		)
	)
	(symbol
		(lib_id "antmicropower:GND")
		(at 140.97 119.38 0)
		(unit 1)
		(exclude_from_sim no)
		(in_bom yes)
		(on_board yes)
		(dnp no)
		(property "Reference" "#PWR050"
			(at 149.86 121.92 0)
			(effects
				(font
					(size 1.27 1.27)
					(thickness 0.15)
				)
				(justify left bottom)
				(hide yes)
			)
		)
		(property "Value" "GND"
			(at 140.97 123.19 0)
			(effects
				(font
					(size 1.27 1.27)
					(thickness 0.15)
				)
			)
		)
		(property "Footprint" ""
			(at 149.86 127 0)
			(effects
				(font
					(size 1.27 1.27)
					(thickness 0.15)
				)
				(justify left bottom)
				(hide yes)
			)
		)
		(property "Datasheet" ""
			(at 149.86 132.08 0)
			(effects
				(font
					(size 1.27 1.27)
					(thickness 0.15)
				)
				(justify left bottom)
				(hide yes)
			)
		)
		(property "Description" ""
			(at 140.97 119.38 0)
			(effects
				(font
					(size 1.27 1.27)
				)
				(hide yes)
			)
		)
		(property "Author" "Antmicro"
			(at 149.86 127 0)
			(effects
				(font
					(size 1.27 1.27)
					(thickness 0.15)
				)
				(justify left bottom)
				(hide yes)
			)
		)
		(property "License" "Apache-2.0"
			(at 149.86 129.54 0)
			(effects
				(font
					(size 1.27 1.27)
					(thickness 0.15)
				)
				(justify left bottom)
				(hide yes)
			)
		)
		(pin "1"
		)
		(instances
			(project "oculink-to-pcie-adapter"
				(path ""
					(reference "#PWR050")
					(unit 1)
				)
			)
		)
	)
	(symbol
		(lib_id "antmicropower:PWR_FLAG")
		(at 331.47 191.77 0)
		(unit 1)
		(exclude_from_sim no)
		(in_bom yes)
		(on_board yes)
		(dnp no)
		(property "Reference" "#FLG04"
			(at 331.47 189.865 0)
			(effects
				(font
					(size 1.27 1.27)
				)
				(hide yes)
			)
		)
		(property "Value" "PWR_FLAG"
			(at 337.82 189.865 0)
			(effects
				(font
					(size 1.27 1.27)
				)
			)
		)
		(property "Footprint" ""
			(at 331.47 191.77 0)
			(effects
				(font
					(size 1.27 1.27)
				)
				(hide yes)
			)
		)
		(property "Datasheet" ""
			(at 331.47 191.77 0)
			(effects
				(font
					(size 1.27 1.27)
				)
				(hide yes)
			)
		)
		(property "Description" ""
			(at 331.47 191.77 0)
			(effects
				(font
					(size 1.27 1.27)
				)
				(hide yes)
			)
		)
		(pin "1"
		)
		(instances
			(project "oculink-to-pcie-adapter"
				(path ""
					(reference "#FLG04")
					(unit 1)
				)
			)
		)
	)
	(symbol
		(lib_id "antmicroResistors0402:R_0R_0402")
		(at 146.05 226.06 0)
		(unit 1)
		(exclude_from_sim no)
		(in_bom yes)
		(on_board yes)
		(dnp no)
		(property "Reference" "R30"
			(at 148.59 224.028 0)
			(effects
				(font
					(size 1.27 1.27)
				)
			)
		)
		(property "Value" "R_0R_0402"
			(at 146.05 229.87 0)
			(effects
				(font
					(size 1.27 1.27)
				)
				(justify left)
				(hide yes)
			)
		)
		(property "Footprint" "antmicro-footprints:R_0402_1005Metric"
			(at 151.13 220.98 0)
			(effects
				(font
					(size 1.27 1.27)
					(thickness 0.15)
				)
				(justify left bottom)
				(hide yes)
			)
		)
		(property "Datasheet" "https://industrial.panasonic.com/cdbs/www-data/pdf/RDA0000/AOA0000C301.pdf"
			(at 146.05 226.06 0)
			(effects
				(font
					(size 1.27 1.27)
					(thickness 0.15)
				)
				(justify left bottom)
				(hide yes)
			)
		)
		(property "Description" "SMD Chip Resistor, Jumper, 0 ohm, 100 mW, 0402 [1005 Metric], Thick Film, General Purpose"
			(at 146.05 226.06 0)
			(effects
				(font
					(size 1.27 1.27)
				)
				(hide yes)
			)
		)
		(property "Manufacturer" "Panasonic"
			(at 151.13 215.9 0)
			(effects
				(font
					(size 1.27 1.27)
					(thickness 0.15)
				)
				(justify left bottom)
				(hide yes)
			)
		)
		(property "MPN" "ERJ2GE0R00X"
			(at 151.13 218.44 0)
			(effects
				(font
					(size 1.27 1.27)
					(thickness 0.15)
				)
				(justify left bottom)
				(hide yes)
			)
		)
		(property "Val" "0R"
			(at 148.59 228.346 0)
			(effects
				(font
					(size 1.27 1.27)
					(thickness 0.15)
				)
			)
		)
		(property "License" "Apache-2.0"
			(at 166.37 251.46 0)
			(effects
				(font
					(size 1.27 1.27)
					(thickness 0.15)
				)
				(justify left bottom)
				(hide yes)
			)
		)
		(property "Author" "Antmicro"
			(at 166.37 254 0)
			(effects
				(font
					(size 1.27 1.27)
					(thickness 0.15)
				)
				(justify left bottom)
				(hide yes)
			)
		)
		(property "Tolerance" "~"
			(at 166.37 236.22 0)
			(effects
				(font
					(size 1.27 1.27)
				)
				(justify left bottom)
				(hide yes)
			)
		)
		(property "Current" "1A"
			(at 147.32 226.695 0)
			(effects
				(font
					(size 1.27 1.27)
					(thickness 0.15)
				)
				(justify left bottom)
				(hide yes)
			)
		)
		(pin "1"
		)
		(pin "2"
		)
		(instances
			(project "oculink-to-pcie-adapter"
				(path ""
					(reference "R30")
					(unit 1)
				)
			)
		)
	)
	(symbol
		(lib_id "antmicroCapacitors0402:C_100n_0402")
		(at 250.19 218.44 90)
		(unit 1)
		(exclude_from_sim no)
		(in_bom yes)
		(on_board yes)
		(dnp no)
		(property "Reference" "C31"
			(at 252.222 214.63 90)
			(effects
				(font
					(size 1.27 1.27)
					(thickness 0.15)
				)
				(justify right)
			)
		)
		(property "Value" "C_100n_0402"
			(at 260.35 198.12 0)
			(effects
				(font
					(size 1.27 1.27)
					(thickness 0.15)
				)
				(justify left bottom)
				(hide yes)
			)
		)
		(property "Footprint" "antmicro-footprints:C_0402_1005Metric"
			(at 262.89 198.12 0)
			(effects
				(font
					(size 1.27 1.27)
					(thickness 0.15)
				)
				(justify left bottom)
				(hide yes)
			)
		)
		(property "Datasheet" "https://www.murata.com/products/productdetail?partno=GRM155R61H104KE14%23"
			(at 265.43 198.12 0)
			(effects
				(font
					(size 1.27 1.27)
					(thickness 0.15)
				)
				(justify left bottom)
				(hide yes)
			)
		)
		(property "Description" "SMD Multilayer Ceramic Capacitor, 0.1 µF, 50 V, 0402 [1005 Metric], ± 10%, X5R, GRM Series"
			(at 250.19 218.44 0)
			(effects
				(font
					(size 1.27 1.27)
				)
				(hide yes)
			)
		)
		(property "MPN" "GRM155R61H104KE14D"
			(at 267.97 198.12 0)
			(effects
				(font
					(size 1.27 1.27)
					(thickness 0.15)
				)
				(justify left bottom)
				(hide yes)
			)
		)
		(property "Manufacturer" "Murata"
			(at 270.51 198.12 0)
			(effects
				(font
					(size 1.27 1.27)
					(thickness 0.15)
				)
				(justify left bottom)
				(hide yes)
			)
		)
		(property "License" "Apache-2.0"
			(at 273.05 198.12 0)
			(effects
				(font
					(size 1.27 1.27)
					(thickness 0.15)
				)
				(justify left bottom)
				(hide yes)
			)
		)
		(property "Author" "Antmicro"
			(at 275.59 198.12 0)
			(effects
				(font
					(size 1.27 1.27)
					(thickness 0.15)
				)
				(justify left bottom)
				(hide yes)
			)
		)
		(property "Val" "100n"
			(at 252.222 217.17 90)
			(effects
				(font
					(size 1.27 1.27)
					(thickness 0.15)
				)
				(justify right)
			)
		)
		(property "Voltage" "50V"
			(at 278.13 198.12 0)
			(effects
				(font
					(size 1.27 1.27)
				)
				(justify left bottom)
				(hide yes)
			)
		)
		(property "Dielectric" "X5R"
			(at 280.67 198.12 0)
			(effects
				(font
					(size 1.27 1.27)
				)
				(justify left bottom)
				(hide yes)
			)
		)
		(pin "1"
		)
		(pin "2"
		)
		(instances
			(project "oculink-to-pcie-adapter"
				(path ""
					(reference "C31")
					(unit 1)
				)
			)
		)
	)
	(symbol
		(lib_id "antmicropower:GND")
		(at 80.01 101.6 0)
		(mirror y)
		(unit 1)
		(exclude_from_sim no)
		(in_bom yes)
		(on_board yes)
		(dnp no)
		(property "Reference" "#PWR039"
			(at 71.12 104.14 0)
			(effects
				(font
					(size 1.27 1.27)
					(thickness 0.15)
				)
				(justify left bottom)
				(hide yes)
			)
		)
		(property "Value" "GND"
			(at 80.01 105.41 0)
			(effects
				(font
					(size 1.27 1.27)
					(thickness 0.15)
				)
			)
		)
		(property "Footprint" ""
			(at 71.12 109.22 0)
			(effects
				(font
					(size 1.27 1.27)
					(thickness 0.15)
				)
				(justify left bottom)
				(hide yes)
			)
		)
		(property "Datasheet" ""
			(at 71.12 114.3 0)
			(effects
				(font
					(size 1.27 1.27)
					(thickness 0.15)
				)
				(justify left bottom)
				(hide yes)
			)
		)
		(property "Description" ""
			(at 80.01 101.6 0)
			(effects
				(font
					(size 1.27 1.27)
				)
				(hide yes)
			)
		)
		(property "Author" "Antmicro"
			(at 71.12 109.22 0)
			(effects
				(font
					(size 1.27 1.27)
					(thickness 0.15)
				)
				(justify left bottom)
				(hide yes)
			)
		)
		(property "License" "Apache-2.0"
			(at 71.12 111.76 0)
			(effects
				(font
					(size 1.27 1.27)
					(thickness 0.15)
				)
				(justify left bottom)
				(hide yes)
			)
		)
		(pin "1"
		)
		(instances
			(project "oculink-to-pcie-adapter"
				(path ""
					(reference "#PWR039")
					(unit 1)
				)
			)
		)
	)
	(symbol
		(lib_id "antmicroTransistorsFETsMOSFETsSingle:BSS138-7-F")
		(at 278.13 124.46 0)
		(unit 1)
		(exclude_from_sim no)
		(in_bom yes)
		(on_board yes)
		(dnp no)
		(property "Reference" "Q9"
			(at 288.29 120.65 0)
			(effects
				(font
					(size 1.27 1.27)
					(thickness 0.15)
				)
				(justify left)
			)
		)
		(property "Value" "BSS138-7-F"
			(at 300.99 129.54 0)
			(effects
				(font
					(size 1.27 1.27)
					(thickness 0.15)
				)
				(justify left bottom)
				(hide yes)
			)
		)
		(property "Footprint" "antmicro-footprints:SOT-23-3"
			(at 300.99 132.08 0)
			(effects
				(font
					(size 1.27 1.27)
					(thickness 0.15)
				)
				(justify left bottom)
				(hide yes)
			)
		)
		(property "Datasheet" "https://www.diodes.com/assets/Datasheets/ds30144.pdf"
			(at 300.99 134.62 0)
			(effects
				(font
					(size 1.27 1.27)
					(thickness 0.15)
				)
				(justify left bottom)
				(hide yes)
			)
		)
		(property "Description" "Power MOSFET, N Channel, 50 V, 200 mA, 1.4 ohm, SOT-23, Surface Mount"
			(at 338.074 146.304 0)
			(effects
				(font
					(size 1.27 1.27)
				)
				(hide yes)
			)
		)
		(property "MPN" "BSS138-7-F"
			(at 288.29 123.19 0)
			(effects
				(font
					(size 1.27 1.27)
					(thickness 0.15)
				)
				(justify left)
			)
		)
		(property "Manufacturer" "Diodes Incorporated"
			(at 300.99 139.7 0)
			(effects
				(font
					(size 1.27 1.27)
					(thickness 0.15)
				)
				(justify left bottom)
				(hide yes)
			)
		)
		(property "Author" "Antmicro"
			(at 300.99 142.24 0)
			(effects
				(font
					(size 1.27 1.27)
					(thickness 0.15)
				)
				(justify left bottom)
				(hide yes)
			)
		)
		(property "License" "Apache-2.0"
			(at 300.99 144.78 0)
			(effects
				(font
					(size 1.27 1.27)
					(thickness 0.15)
				)
				(justify left bottom)
				(hide yes)
			)
		)
		(pin "2"
		)
		(pin "3"
		)
		(pin "1"
		)
		(instances
			(project "oculink-to-pcie-adapter"
				(path ""
					(reference "Q9")
					(unit 1)
				)
			)
		)
	)
	(symbol
		(lib_id "antmicropower:GND")
		(at 285.75 133.35 0)
		(mirror y)
		(unit 1)
		(exclude_from_sim no)
		(in_bom yes)
		(on_board yes)
		(dnp no)
		(property "Reference" "#PWR063"
			(at 276.86 135.89 0)
			(effects
				(font
					(size 1.27 1.27)
					(thickness 0.15)
				)
				(justify left bottom)
				(hide yes)
			)
		)
		(property "Value" "GND"
			(at 285.75 137.16 0)
			(effects
				(font
					(size 1.27 1.27)
					(thickness 0.15)
				)
			)
		)
		(property "Footprint" ""
			(at 276.86 140.97 0)
			(effects
				(font
					(size 1.27 1.27)
					(thickness 0.15)
				)
				(justify left bottom)
				(hide yes)
			)
		)
		(property "Datasheet" ""
			(at 276.86 146.05 0)
			(effects
				(font
					(size 1.27 1.27)
					(thickness 0.15)
				)
				(justify left bottom)
				(hide yes)
			)
		)
		(property "Description" ""
			(at 285.75 133.35 0)
			(effects
				(font
					(size 1.27 1.27)
				)
				(hide yes)
			)
		)
		(property "Author" "Antmicro"
			(at 276.86 140.97 0)
			(effects
				(font
					(size 1.27 1.27)
					(thickness 0.15)
				)
				(justify left bottom)
				(hide yes)
			)
		)
		(property "License" "Apache-2.0"
			(at 276.86 143.51 0)
			(effects
				(font
					(size 1.27 1.27)
					(thickness 0.15)
				)
				(justify left bottom)
				(hide yes)
			)
		)
		(pin "1"
		)
		(instances
			(project "oculink-to-pcie-adapter"
				(path ""
					(reference "#PWR063")
					(unit 1)
				)
			)
		)
	)
	(symbol
		(lib_id "antmicroResistors0402:R_1k_0402")
		(at 381 68.58 90)
		(unit 1)
		(exclude_from_sim no)
		(in_bom no)
		(on_board yes)
		(dnp yes)
		(property "Reference" "R22"
			(at 382.27 64.77 90)
			(effects
				(font
					(size 1.27 1.27)
					(thickness 0.15)
				)
				(justify right)
			)
		)
		(property "Value" "R_1k_0402"
			(at 393.7 48.26 0)
			(effects
				(font
					(size 1.27 1.27)
					(thickness 0.15)
				)
				(justify left bottom)
				(hide yes)
			)
		)
		(property "Footprint" "antmicro-footprints:R_0402_1005Metric"
			(at 396.24 48.26 0)
			(effects
				(font
					(size 1.27 1.27)
					(thickness 0.15)
				)
				(justify left bottom)
				(hide yes)
			)
		)
		(property "Datasheet" "https://www.bourns.com/docs/product-datasheets/cr.pdf"
			(at 398.78 48.26 0)
			(effects
				(font
					(size 1.27 1.27)
					(thickness 0.15)
				)
				(justify left bottom)
				(hide yes)
			)
		)
		(property "Description" "SMD Chip Resistor, 1 kohm, ± 1%, 63 mW, 0402 [1005 Metric], Thick Film, General Purpose"
			(at 381 68.58 0)
			(effects
				(font
					(size 1.27 1.27)
				)
				(hide yes)
			)
		)
		(property "MPN" "CR0402-FX-1001GLF"
			(at 401.32 48.26 0)
			(effects
				(font
					(size 1.27 1.27)
					(thickness 0.15)
				)
				(justify left bottom)
				(hide yes)
			)
		)
		(property "Manufacturer" "Bourns"
			(at 403.86 48.26 0)
			(effects
				(font
					(size 1.27 1.27)
					(thickness 0.15)
				)
				(justify left bottom)
				(hide yes)
			)
		)
		(property "License" "Apache-2.0"
			(at 406.4 48.26 0)
			(effects
				(font
					(size 1.27 1.27)
					(thickness 0.15)
				)
				(justify left bottom)
				(hide yes)
			)
		)
		(property "Author" "Antmicro"
			(at 408.94 48.26 0)
			(effects
				(font
					(size 1.27 1.27)
					(thickness 0.15)
				)
				(justify left bottom)
				(hide yes)
			)
		)
		(property "Val" "1k"
			(at 382.27 67.31 90)
			(effects
				(font
					(size 1.27 1.27)
					(thickness 0.15)
				)
				(justify right)
			)
		)
		(property "Tolerance" "1%"
			(at 391.16 48.26 0)
			(effects
				(font
					(size 1.27 1.27)
				)
				(justify left bottom)
				(hide yes)
			)
		)
		(pin "2"
		)
		(pin "1"
		)
		(instances
			(project "oculink-to-pcie-adapter"
				(path ""
					(reference "R22")
					(unit 1)
				)
			)
		)
	)
	(symbol
		(lib_id "antmicropower:VBUS")
		(at 303.53 50.8 0)
		(unit 1)
		(exclude_from_sim no)
		(in_bom yes)
		(on_board yes)
		(dnp no)
		(property "Reference" "#PWR048"
			(at 303.53 54.61 0)
			(effects
				(font
					(size 1.27 1.27)
				)
				(hide yes)
			)
		)
		(property "Value" "VBUS"
			(at 303.53 46.99 0)
			(effects
				(font
					(size 1.27 1.27)
				)
			)
		)
		(property "Footprint" ""
			(at 303.53 50.8 0)
			(effects
				(font
					(size 1.27 1.27)
				)
				(hide yes)
			)
		)
		(property "Datasheet" ""
			(at 303.53 50.8 0)
			(effects
				(font
					(size 1.27 1.27)
				)
				(hide yes)
			)
		)
		(property "Description" ""
			(at 303.53 50.8 0)
			(effects
				(font
					(size 1.27 1.27)
				)
				(hide yes)
			)
		)
		(pin "1"
		)
		(instances
			(project "oculink-to-pcie-adapter"
				(path ""
					(reference "#PWR048")
					(unit 1)
				)
			)
		)
	)
	(symbol
		(lib_id "antmicroTVSDiodes:ESDA25P35-1U1M")
		(at 80.01 82.55 270)
		(unit 1)
		(exclude_from_sim no)
		(in_bom yes)
		(on_board yes)
		(dnp no)
		(fields_autoplaced yes)
		(property "Reference" "D21"
			(at 82.55 83.82 90)
			(effects
				(font
					(size 1.27 1.27)
					(thickness 0.15)
				)
				(justify left)
			)
		)
		(property "Value" "ESDA25P35-1U1M"
			(at 64.77 106.68 0)
			(effects
				(font
					(size 1.27 1.27)
					(thickness 0.15)
				)
				(justify left bottom)
				(hide yes)
			)
		)
		(property "Footprint" "antmicro-footprints:QFN-2L_1.6x1x0.55mm"
			(at 69.85 106.68 0)
			(effects
				(font
					(size 1.27 1.27)
					(thickness 0.15)
				)
				(justify left bottom)
				(hide yes)
			)
		)
		(property "Datasheet" "https://www.st.com/resource/en/datasheet/esda25p35-1u1m.pdf"
			(at 67.31 106.68 0)
			(effects
				(font
					(size 1.27 1.27)
					(thickness 0.15)
				)
				(justify left bottom)
				(hide yes)
			)
		)
		(property "Description" "Unidirectional TVS, 30 kV, QFN-2L, 22 V, 195 pF"
			(at 80.01 82.55 0)
			(effects
				(font
					(size 1.27 1.27)
				)
				(hide yes)
			)
		)
		(property "MPN" "ESDA25P35-1U1M"
			(at 82.55 86.36 90)
			(effects
				(font
					(size 1.27 1.27)
					(thickness 0.15)
				)
				(justify left)
			)
		)
		(property "Manufacturer" "STMicroelectronics"
			(at 62.23 106.68 0)
			(effects
				(font
					(size 1.27 1.27)
					(thickness 0.15)
				)
				(justify left bottom)
				(hide yes)
			)
		)
		(property "Author" "Antmicro"
			(at 59.69 106.68 0)
			(effects
				(font
					(size 1.27 1.27)
					(thickness 0.15)
				)
				(justify left bottom)
				(hide yes)
			)
		)
		(property "License" "Apache-2.0"
			(at 57.15 106.68 0)
			(effects
				(font
					(size 1.27 1.27)
					(thickness 0.15)
				)
				(justify left bottom)
				(hide yes)
			)
		)
		(pin "2"
		)
		(pin "1"
		)
		(instances
			(project "oculink-to-pcie-adapter"
				(path ""
					(reference "D21")
					(unit 1)
				)
			)
		)
	)
	(symbol
		(lib_id "antmicroResistors0402:R_100k_0402")
		(at 215.9 220.98 0)
		(unit 1)
		(exclude_from_sim no)
		(in_bom yes)
		(on_board yes)
		(dnp no)
		(property "Reference" "R34"
			(at 218.44 218.694 0)
			(effects
				(font
					(size 1.27 1.27)
				)
			)
		)
		(property "Value" "R_100k_0402"
			(at 215.9 224.79 0)
			(effects
				(font
					(size 1.27 1.27)
				)
				(justify left)
				(hide yes)
			)
		)
		(property "Footprint" "antmicro-footprints:R_0402_1005Metric"
			(at 220.98 215.9 0)
			(effects
				(font
					(size 1.27 1.27)
					(thickness 0.15)
				)
				(justify left bottom)
				(hide yes)
			)
		)
		(property "Datasheet" "https://www.bourns.com/docs/product-datasheets/cr.pdf"
			(at 215.9 220.98 0)
			(effects
				(font
					(size 1.27 1.27)
					(thickness 0.15)
				)
				(justify left bottom)
				(hide yes)
			)
		)
		(property "Description" "SMD Chip Resistor, 100 kohm, ± 1%, 62.5 mW, 0402 [1005 Metric], Thick Film, General Purpose"
			(at 215.9 220.98 0)
			(effects
				(font
					(size 1.27 1.27)
				)
				(hide yes)
			)
		)
		(property "Manufacturer" "Bourns"
			(at 220.98 210.82 0)
			(effects
				(font
					(size 1.27 1.27)
					(thickness 0.15)
				)
				(justify left bottom)
				(hide yes)
			)
		)
		(property "MPN" "CR0402-FX-1003GLF"
			(at 220.98 213.36 0)
			(effects
				(font
					(size 1.27 1.27)
					(thickness 0.15)
				)
				(justify left bottom)
				(hide yes)
			)
		)
		(property "Val" "100k"
			(at 218.44 223.266 0)
			(effects
				(font
					(size 1.27 1.27)
					(thickness 0.15)
				)
			)
		)
		(property "License" "Apache-2.0"
			(at 236.22 246.38 0)
			(effects
				(font
					(size 1.27 1.27)
					(thickness 0.15)
				)
				(justify left bottom)
				(hide yes)
			)
		)
		(property "Author" "Antmicro"
			(at 236.22 248.92 0)
			(effects
				(font
					(size 1.27 1.27)
					(thickness 0.15)
				)
				(justify left bottom)
				(hide yes)
			)
		)
		(property "Tolerance" "1%"
			(at 236.22 231.14 0)
			(effects
				(font
					(size 1.27 1.27)
				)
				(justify left bottom)
				(hide yes)
			)
		)
		(pin "1"
		)
		(pin "2"
		)
		(instances
			(project "oculink-to-pcie-adapter"
				(path ""
					(reference "R34")
					(unit 1)
				)
			)
		)
	)
	(symbol
		(lib_id "antmicroCapacitors0402:C_100n_0402")
		(at 152.4 201.93 90)
		(unit 1)
		(exclude_from_sim no)
		(in_bom yes)
		(on_board yes)
		(dnp no)
		(fields_autoplaced yes)
		(property "Reference" "C26"
			(at 154.94 198.1136 90)
			(effects
				(font
					(size 1.27 1.27)
					(thickness 0.15)
				)
				(justify right)
			)
		)
		(property "Value" "C_100n_0402"
			(at 162.56 181.61 0)
			(effects
				(font
					(size 1.27 1.27)
					(thickness 0.15)
				)
				(justify left bottom)
				(hide yes)
			)
		)
		(property "Footprint" "antmicro-footprints:C_0402_1005Metric"
			(at 165.1 181.61 0)
			(effects
				(font
					(size 1.27 1.27)
					(thickness 0.15)
				)
				(justify left bottom)
				(hide yes)
			)
		)
		(property "Datasheet" "https://www.murata.com/products/productdetail?partno=GRM155R61H104KE14%23"
			(at 167.64 181.61 0)
			(effects
				(font
					(size 1.27 1.27)
					(thickness 0.15)
				)
				(justify left bottom)
				(hide yes)
			)
		)
		(property "Description" "SMD Multilayer Ceramic Capacitor, 0.1 µF, 50 V, 0402 [1005 Metric], ± 10%, X5R, GRM Series"
			(at 152.4 201.93 0)
			(effects
				(font
					(size 1.27 1.27)
				)
				(hide yes)
			)
		)
		(property "MPN" "GRM155R61H104KE14D"
			(at 170.18 181.61 0)
			(effects
				(font
					(size 1.27 1.27)
					(thickness 0.15)
				)
				(justify left bottom)
				(hide yes)
			)
		)
		(property "Manufacturer" "Murata"
			(at 172.72 181.61 0)
			(effects
				(font
					(size 1.27 1.27)
					(thickness 0.15)
				)
				(justify left bottom)
				(hide yes)
			)
		)
		(property "License" "Apache-2.0"
			(at 175.26 181.61 0)
			(effects
				(font
					(size 1.27 1.27)
					(thickness 0.15)
				)
				(justify left bottom)
				(hide yes)
			)
		)
		(property "Author" "Antmicro"
			(at 177.8 181.61 0)
			(effects
				(font
					(size 1.27 1.27)
					(thickness 0.15)
				)
				(justify left bottom)
				(hide yes)
			)
		)
		(property "Val" "100n"
			(at 154.94 200.6536 90)
			(effects
				(font
					(size 1.27 1.27)
					(thickness 0.15)
				)
				(justify right)
			)
		)
		(property "Voltage" "50V"
			(at 180.34 181.61 0)
			(effects
				(font
					(size 1.27 1.27)
				)
				(justify left bottom)
				(hide yes)
			)
		)
		(property "Dielectric" "X5R"
			(at 182.88 181.61 0)
			(effects
				(font
					(size 1.27 1.27)
				)
				(justify left bottom)
				(hide yes)
			)
		)
		(pin "1"
		)
		(pin "2"
		)
		(instances
			(project "oculink-to-pcie-adapter"
				(path ""
					(reference "C26")
					(unit 1)
				)
			)
		)
	)
	(symbol
		(lib_id "antmicroCapacitorspol:C_Pol_150u_30V_Vishay-T59-EE")
		(at 115.57 196.85 270)
		(unit 1)
		(exclude_from_sim no)
		(in_bom yes)
		(on_board yes)
		(dnp no)
		(fields_autoplaced yes)
		(property "Reference" "C43"
			(at 118.11 197.5866 90)
			(effects
				(font
					(size 1.27 1.27)
					(thickness 0.15)
				)
				(justify left)
			)
		)
		(property "Value" "C_Pol_150u_30V_Vishay-T59-EE"
			(at 105.41 212.09 0)
			(effects
				(font
					(size 1.27 1.27)
					(thickness 0.15)
				)
				(justify left bottom)
				(hide yes)
			)
		)
		(property "Footprint" "antmicro-footprints:C_Pol_Vishay-T59-EE"
			(at 102.87 212.09 0)
			(effects
				(font
					(size 1.27 1.27)
					(thickness 0.15)
				)
				(justify left bottom)
				(hide yes)
			)
		)
		(property "Datasheet" "https://www.vishay.com/docs/40191/t59.pdf"
			(at 100.33 212.09 0)
			(effects
				(font
					(size 1.27 1.27)
					(thickness 0.15)
				)
				(justify left bottom)
				(hide yes)
			)
		)
		(property "Description" "Tantalum Capacitors - Polymer 150uF 30volts 20% 75mohms maxESR"
			(at 115.57 196.85 0)
			(effects
				(font
					(size 1.27 1.27)
				)
				(hide yes)
			)
		)
		(property "MPN" "T59EE157M030C0075"
			(at 102.87 210.82 0)
			(effects
				(font
					(size 1.27 1.27)
				)
				(justify left bottom)
				(hide yes)
			)
		)
		(property "Manufacturer" "Vishay"
			(at 97.79 212.09 0)
			(effects
				(font
					(size 1.27 1.27)
					(thickness 0.15)
				)
				(justify left bottom)
				(hide yes)
			)
		)
		(property "Voltage" "30V"
			(at 95.25 212.09 0)
			(effects
				(font
					(size 1.27 1.27)
					(thickness 0.15)
				)
				(justify left bottom)
				(hide yes)
			)
		)
		(property "Val" "150u"
			(at 118.11 200.1266 90)
			(effects
				(font
					(size 1.27 1.27)
					(thickness 0.15)
				)
				(justify left)
			)
		)
		(property "Author" "Antmicro"
			(at 92.71 212.09 0)
			(effects
				(font
					(size 1.27 1.27)
					(thickness 0.15)
				)
				(justify left bottom)
				(hide yes)
			)
		)
		(property "License" "Apache-2.0"
			(at 90.17 212.09 0)
			(effects
				(font
					(size 1.27 1.27)
					(thickness 0.15)
				)
				(justify left bottom)
				(hide yes)
			)
		)
		(property "Dielectric" "template_dielectric"
			(at 90.17 210.82 0)
			(effects
				(font
					(size 1.27 1.27)
				)
				(justify left bottom)
				(hide yes)
			)
		)
		(pin "2"
		)
		(pin "1"
		)
		(instances
			(project "oculink-to-pcie-adapter"
				(path ""
					(reference "C43")
					(unit 1)
				)
			)
		)
	)
	(symbol
		(lib_id "antmicroResistors0402:R_10k_0.1%_0402")
		(at 242.57 229.87 90)
		(unit 1)
		(exclude_from_sim no)
		(in_bom yes)
		(on_board yes)
		(dnp no)
		(property "Reference" "R39"
			(at 243.84 226.06 90)
			(effects
				(font
					(size 1.27 1.27)
					(thickness 0.15)
				)
				(justify right)
			)
		)
		(property "Value" "R_10k_0.1%_0402"
			(at 255.27 209.55 0)
			(effects
				(font
					(size 1.27 1.27)
					(thickness 0.15)
				)
				(justify left bottom)
				(hide yes)
			)
		)
		(property "Footprint" "antmicro-footprints:R_0402_1005Metric"
			(at 257.81 209.55 0)
			(effects
				(font
					(size 1.27 1.27)
					(thickness 0.15)
				)
				(justify left bottom)
				(hide yes)
			)
		)
		(property "Datasheet" "https://www.mouser.com/datasheet/2/54/CRT-1649066.pdf"
			(at 260.35 209.55 0)
			(effects
				(font
					(size 1.27 1.27)
					(thickness 0.15)
				)
				(justify left bottom)
				(hide yes)
			)
		)
		(property "Description" "SMD Chip Resistor, 10 kohm, ± 0.1%, 62.5 mW, 0402 [1005 Metric], Thin Film, Precision Resistors"
			(at 242.57 229.87 0)
			(effects
				(font
					(size 1.27 1.27)
				)
				(hide yes)
			)
		)
		(property "MPN" "CRT0402-BY-1002GLF "
			(at 245.11 226.06 0)
			(effects
				(font
					(size 1.27 1.27)
					(thickness 0.15)
				)
				(justify left bottom)
				(hide yes)
			)
		)
		(property "Val" "10k"
			(at 243.84 228.6 90)
			(effects
				(font
					(size 1.27 1.27)
					(thickness 0.15)
				)
				(justify right)
			)
		)
		(property "Manufacturer" "Bourns"
			(at 265.43 209.55 0)
			(effects
				(font
					(size 1.27 1.27)
					(thickness 0.15)
				)
				(justify left bottom)
				(hide yes)
			)
		)
		(property "Tolerance" "0.1%"
			(at 245.11 231.14 0)
			(effects
				(font
					(size 1.27 1.27)
					(thickness 0.15)
				)
				(justify left bottom)
				(hide yes)
			)
		)
		(property "License" "Apache-2.0"
			(at 267.97 209.55 0)
			(effects
				(font
					(size 1.27 1.27)
					(thickness 0.15)
				)
				(justify left bottom)
				(hide yes)
			)
		)
		(property "Author" "Antmicro"
			(at 270.51 209.55 0)
			(effects
				(font
					(size 1.27 1.27)
					(thickness 0.15)
				)
				(justify left bottom)
				(hide yes)
			)
		)
		(pin "2"
		)
		(pin "1"
		)
		(instances
			(project "oculink-to-pcie-adapter"
				(path ""
					(reference "R39")
					(unit 1)
				)
			)
		)
	)
	(symbol
		(lib_id "antmicroResistors0603:R_0R_22.4A_0603")
		(at 320.04 194.31 0)
		(mirror y)
		(unit 1)
		(exclude_from_sim no)
		(in_bom no)
		(on_board yes)
		(dnp no)
		(property "Reference" "R26"
			(at 317.5 191.77 0)
			(effects
				(font
					(size 1.27 1.27)
					(thickness 0.15)
				)
			)
		)
		(property "Value" "R_0R_22.4A_0603"
			(at 316.23 196.088 90)
			(effects
				(font
					(size 1.27 1.27)
					(thickness 0.15)
				)
				(justify right)
				(hide yes)
			)
		)
		(property "Footprint" "antmicro-footprints:R_0603_1608Metric"
			(at 304.8 204.47 0)
			(effects
				(font
					(size 1.27 1.27)
					(thickness 0.15)
				)
				(justify left bottom)
				(hide yes)
			)
		)
		(property "Datasheet" "https://fscdn.rohm.com/en/products/databook/datasheet/passive/resistor/chip_resistor/pmr-jpw-e.pdf"
			(at 304.8 207.01 0)
			(effects
				(font
					(size 1.27 1.27)
					(thickness 0.15)
				)
				(justify left bottom)
				(hide yes)
			)
		)
		(property "Description" "SMD Chip Resistor"
			(at 320.04 194.31 0)
			(effects
				(font
					(size 1.27 1.27)
				)
				(hide yes)
			)
		)
		(property "MPN" "PMR03EZPJ000"
			(at 304.8 209.55 0)
			(effects
				(font
					(size 1.27 1.27)
					(thickness 0.15)
				)
				(justify left bottom)
				(hide yes)
			)
		)
		(property "Manufacturer" "ROHM Semiconductor"
			(at 304.8 212.09 0)
			(effects
				(font
					(size 1.27 1.27)
					(thickness 0.15)
				)
				(justify left bottom)
				(hide yes)
			)
		)
		(property "Val" "0R"
			(at 313.69 195.58 0)
			(effects
				(font
					(size 1.27 1.27)
					(thickness 0.15)
				)
			)
		)
		(property "Max. Curr." "22.4A"
			(at 322.58 195.58 0)
			(effects
				(font
					(size 1.27 1.27)
					(thickness 0.15)
				)
			)
		)
		(property "Author" "Antmicro"
			(at 304.8 217.17 0)
			(effects
				(font
					(size 1.27 1.27)
					(thickness 0.15)
				)
				(justify left bottom)
				(hide yes)
			)
		)
		(property "License" "Apache-2.0"
			(at 304.8 219.71 0)
			(effects
				(font
					(size 1.27 1.27)
					(thickness 0.15)
				)
				(justify left bottom)
				(hide yes)
			)
		)
		(property "Tolerance" "template_tolerance"
			(at 299.72 204.47 0)
			(effects
				(font
					(size 1.27 1.27)
				)
				(justify left bottom)
				(hide yes)
			)
		)
		(pin "1"
		)
		(pin "2"
		)
		(instances
			(project "oculink-to-pcie-adapter"
				(path ""
					(reference "R26")
					(unit 1)
				)
			)
		)
	)
	(symbol
		(lib_id "antmicropower:GND")
		(at 115.57 203.2 0)
		(unit 1)
		(exclude_from_sim no)
		(in_bom yes)
		(on_board yes)
		(dnp no)
		(property "Reference" "#PWR090"
			(at 115.57 203.2 0)
			(effects
				(font
					(size 1.27 1.27)
				)
				(justify left)
				(hide yes)
			)
		)
		(property "Value" "GND"
			(at 115.57 207.01 0)
			(effects
				(font
					(size 1.27 1.27)
				)
			)
		)
		(property "Footprint" ""
			(at 115.57 203.2 0)
			(effects
				(font
					(size 1.27 1.27)
					(thickness 0.15)
				)
				(justify left bottom)
				(hide yes)
			)
		)
		(property "Datasheet" ""
			(at 115.57 203.2 0)
			(effects
				(font
					(size 1.27 1.27)
					(thickness 0.15)
				)
				(justify left bottom)
				(hide yes)
			)
		)
		(property "Description" ""
			(at 115.57 203.2 0)
			(effects
				(font
					(size 1.27 1.27)
				)
				(hide yes)
			)
		)
		(property "Author" "Antmicro"
			(at 124.46 210.82 0)
			(effects
				(font
					(size 1.27 1.27)
					(thickness 0.15)
				)
				(justify left bottom)
				(hide yes)
			)
		)
		(property "License" "Apache-2.0"
			(at 124.46 213.36 0)
			(effects
				(font
					(size 1.27 1.27)
					(thickness 0.15)
				)
				(justify left bottom)
				(hide yes)
			)
		)
		(pin "1"
		)
		(instances
			(project "oculink-to-pcie-adapter"
				(path ""
					(reference "#PWR090")
					(unit 1)
				)
			)
		)
	)
	(symbol
		(lib_id "antmicroFixedInductors:L_4u7_14.6A_Abracon-Q8080")
		(at 229.87 194.31 0)
		(unit 1)
		(exclude_from_sim no)
		(in_bom yes)
		(on_board yes)
		(dnp no)
		(fields_autoplaced yes)
		(property "Reference" "L2"
			(at 232.41 189.23 0)
			(effects
				(font
					(size 1.27 1.27)
					(thickness 0.15)
				)
			)
		)
		(property "Value" "L_4u7_14.6A_Abracon-Q8080"
			(at 245.11 204.47 0)
			(effects
				(font
					(size 1.27 1.27)
					(thickness 0.15)
				)
				(justify left bottom)
				(hide yes)
			)
		)
		(property "Footprint" "antmicro-footprints:L_Abracon_ASPIAIG-Q8080"
			(at 245.11 207.01 0)
			(effects
				(font
					(size 1.27 1.27)
					(thickness 0.15)
				)
				(justify left bottom)
				(hide yes)
			)
		)
		(property "Datasheet" "https://www.mouser.com/datasheet/2/3/ASPIAIG_Q8080-2256550.pdf"
			(at 245.11 209.55 0)
			(effects
				(font
					(size 1.27 1.27)
					(thickness 0.15)
				)
				(justify left bottom)
				(hide yes)
			)
		)
		(property "Description" "Power Inductors - SMD 4.7 UH 20%"
			(at 229.87 194.31 0)
			(effects
				(font
					(size 1.27 1.27)
				)
				(hide yes)
			)
		)
		(property "MPN" "ASPIAIG-Q8080-4R7M-T"
			(at 245.11 212.09 0)
			(effects
				(font
					(size 1.27 1.27)
					(thickness 0.15)
				)
				(justify left bottom)
				(hide yes)
			)
		)
		(property "ISat" "17A"
			(at 245.11 214.63 0)
			(effects
				(font
					(size 1.27 1.27)
					(thickness 0.15)
				)
				(justify left bottom)
				(hide yes)
			)
		)
		(property "IMax" "14.6A"
			(at 245.11 217.17 0)
			(effects
				(font
					(size 1.27 1.27)
					(thickness 0.15)
				)
				(justify left bottom)
				(hide yes)
			)
		)
		(property "Size" "8.9x8.5"
			(at 245.11 219.71 0)
			(effects
				(font
					(size 1.27 1.27)
					(thickness 0.15)
				)
				(justify left bottom)
				(hide yes)
			)
		)
		(property "Val" "4.7u/14.6A"
			(at 232.41 191.77 0)
			(effects
				(font
					(size 1.27 1.27)
					(thickness 0.15)
				)
			)
		)
		(property "Author" "Antmicro"
			(at 245.11 222.25 0)
			(effects
				(font
					(size 1.27 1.27)
					(thickness 0.15)
				)
				(justify left bottom)
				(hide yes)
			)
		)
		(property "License" "Apache-2.0"
			(at 245.11 224.79 0)
			(effects
				(font
					(size 1.27 1.27)
					(thickness 0.15)
				)
				(justify left bottom)
				(hide yes)
			)
		)
		(property "Manufacturer" "Abracon"
			(at 245.11 227.33 0)
			(effects
				(font
					(size 1.27 1.27)
					(thickness 0.15)
				)
				(justify left bottom)
				(hide yes)
			)
		)
		(pin "1"
		)
		(pin "2"
		)
		(instances
			(project "oculink-to-pcie-adapter"
				(path ""
					(reference "L2")
					(unit 1)
				)
			)
		)
	)
	(symbol
		(lib_id "antmicroCapacitors0402:C_4u7_25V_0402")
		(at 116.84 233.68 90)
		(unit 1)
		(exclude_from_sim no)
		(in_bom yes)
		(on_board yes)
		(dnp no)
		(property "Reference" "C21"
			(at 118.872 229.87 90)
			(effects
				(font
					(size 1.27 1.27)
					(thickness 0.15)
				)
				(justify right)
			)
		)
		(property "Value" "C_4u7_25V_0402"
			(at 127 213.36 0)
			(effects
				(font
					(size 1.27 1.27)
					(thickness 0.15)
				)
				(justify left bottom)
				(hide yes)
			)
		)
		(property "Footprint" "antmicro-footprints:C_0402_1005Metric"
			(at 129.54 213.36 0)
			(effects
				(font
					(size 1.27 1.27)
					(thickness 0.15)
				)
				(justify left bottom)
				(hide yes)
			)
		)
		(property "Datasheet" "https://www.murata.com/products/productdetail?partno=GRM155C61E475ME15%23"
			(at 132.08 213.36 0)
			(effects
				(font
					(size 1.27 1.27)
					(thickness 0.15)
				)
				(justify left bottom)
				(hide yes)
			)
		)
		(property "Description" "SMD Multilayer Ceramic Capacitor"
			(at 116.84 233.68 0)
			(effects
				(font
					(size 1.27 1.27)
				)
				(hide yes)
			)
		)
		(property "MPN" "GRM155C61E475ME15J"
			(at 134.62 213.36 0)
			(effects
				(font
					(size 1.27 1.27)
					(thickness 0.15)
				)
				(justify left bottom)
				(hide yes)
			)
		)
		(property "Manufacturer" "Murata"
			(at 137.16 213.36 0)
			(effects
				(font
					(size 1.27 1.27)
					(thickness 0.15)
				)
				(justify left bottom)
				(hide yes)
			)
		)
		(property "License" "Apache-2.0"
			(at 139.7 213.36 0)
			(effects
				(font
					(size 1.27 1.27)
					(thickness 0.15)
				)
				(justify left bottom)
				(hide yes)
			)
		)
		(property "Author" "Antmicro"
			(at 142.24 213.36 0)
			(effects
				(font
					(size 1.27 1.27)
					(thickness 0.15)
				)
				(justify left bottom)
				(hide yes)
			)
		)
		(property "Val" "4u7"
			(at 118.872 232.41 90)
			(effects
				(font
					(size 1.27 1.27)
					(thickness 0.15)
				)
				(justify right)
			)
		)
		(property "Voltage" "25V"
			(at 144.78 213.36 0)
			(effects
				(font
					(size 1.27 1.27)
				)
				(justify left bottom)
				(hide yes)
			)
		)
		(property "Dielectric" "X5S"
			(at 147.32 213.36 0)
			(effects
				(font
					(size 1.27 1.27)
				)
				(justify left bottom)
				(hide yes)
			)
		)
		(pin "2"
		)
		(pin "1"
		)
		(instances
			(project "oculink-to-pcie-adapter"
				(path ""
					(reference "C21")
					(unit 1)
				)
			)
		)
	)
	(symbol
		(lib_id "antmicroResistors0402:R_10k_0402")
		(at 248.92 132.08 90)
		(unit 1)
		(exclude_from_sim no)
		(in_bom yes)
		(on_board yes)
		(dnp no)
		(property "Reference" "R38"
			(at 250.19 128.524 90)
			(effects
				(font
					(size 1.27 1.27)
					(thickness 0.15)
				)
				(justify right)
			)
		)
		(property "Value" "R_10k_0402"
			(at 261.62 111.76 0)
			(effects
				(font
					(size 1.27 1.27)
					(thickness 0.15)
				)
				(justify left bottom)
				(hide yes)
			)
		)
		(property "Footprint" "antmicro-footprints:R_0402_1005Metric"
			(at 264.16 111.76 0)
			(effects
				(font
					(size 1.27 1.27)
					(thickness 0.15)
				)
				(justify left bottom)
				(hide yes)
			)
		)
		(property "Datasheet" "https://www.bourns.com/docs/product-datasheets/cr.pdf"
			(at 266.7 111.76 0)
			(effects
				(font
					(size 1.27 1.27)
					(thickness 0.15)
				)
				(justify left bottom)
				(hide yes)
			)
		)
		(property "Description" "SMD Chip Resistor, 10 kohm, ± 1%, 62.5 mW, 0402 [1005 Metric], Thick Film, General Purpose"
			(at 248.92 132.08 0)
			(effects
				(font
					(size 1.27 1.27)
				)
				(hide yes)
			)
		)
		(property "MPN" "CR0402-FX-1002GLF"
			(at 269.24 111.76 0)
			(effects
				(font
					(size 1.27 1.27)
					(thickness 0.15)
				)
				(justify left bottom)
				(hide yes)
			)
		)
		(property "Manufacturer" "Bourns"
			(at 271.78 111.76 0)
			(effects
				(font
					(size 1.27 1.27)
					(thickness 0.15)
				)
				(justify left bottom)
				(hide yes)
			)
		)
		(property "License" "Apache-2.0"
			(at 274.32 111.76 0)
			(effects
				(font
					(size 1.27 1.27)
					(thickness 0.15)
				)
				(justify left bottom)
				(hide yes)
			)
		)
		(property "Author" "Antmicro"
			(at 276.86 111.76 0)
			(effects
				(font
					(size 1.27 1.27)
					(thickness 0.15)
				)
				(justify left bottom)
				(hide yes)
			)
		)
		(property "Val" "10k"
			(at 250.19 131.064 90)
			(effects
				(font
					(size 1.27 1.27)
					(thickness 0.15)
				)
				(justify right)
			)
		)
		(property "Tolerance" "1%"
			(at 259.08 111.76 0)
			(effects
				(font
					(size 1.27 1.27)
				)
				(justify left bottom)
				(hide yes)
			)
		)
		(pin "2"
		)
		(pin "1"
		)
		(instances
			(project "oculink-to-pcie-adapter"
				(path ""
					(reference "R38")
					(unit 1)
				)
			)
		)
	)
	(symbol
		(lib_id "antmicroResistors0402:R_1k_0402")
		(at 219.71 71.12 90)
		(unit 1)
		(exclude_from_sim no)
		(in_bom yes)
		(on_board yes)
		(dnp no)
		(property "Reference" "R37"
			(at 220.98 67.31 90)
			(effects
				(font
					(size 1.27 1.27)
					(thickness 0.15)
				)
				(justify right)
			)
		)
		(property "Value" "R_1k_0402"
			(at 232.41 50.8 0)
			(effects
				(font
					(size 1.27 1.27)
					(thickness 0.15)
				)
				(justify left bottom)
				(hide yes)
			)
		)
		(property "Footprint" "antmicro-footprints:R_0402_1005Metric"
			(at 234.95 50.8 0)
			(effects
				(font
					(size 1.27 1.27)
					(thickness 0.15)
				)
				(justify left bottom)
				(hide yes)
			)
		)
		(property "Datasheet" "https://www.bourns.com/docs/product-datasheets/cr.pdf"
			(at 237.49 50.8 0)
			(effects
				(font
					(size 1.27 1.27)
					(thickness 0.15)
				)
				(justify left bottom)
				(hide yes)
			)
		)
		(property "Description" "SMD Chip Resistor, 1 kohm, ± 1%, 63 mW, 0402 [1005 Metric], Thick Film, General Purpose"
			(at 219.71 71.12 0)
			(effects
				(font
					(size 1.27 1.27)
				)
				(hide yes)
			)
		)
		(property "MPN" "CR0402-FX-1001GLF"
			(at 240.03 50.8 0)
			(effects
				(font
					(size 1.27 1.27)
					(thickness 0.15)
				)
				(justify left bottom)
				(hide yes)
			)
		)
		(property "Manufacturer" "Bourns"
			(at 242.57 50.8 0)
			(effects
				(font
					(size 1.27 1.27)
					(thickness 0.15)
				)
				(justify left bottom)
				(hide yes)
			)
		)
		(property "License" "Apache-2.0"
			(at 245.11 50.8 0)
			(effects
				(font
					(size 1.27 1.27)
					(thickness 0.15)
				)
				(justify left bottom)
				(hide yes)
			)
		)
		(property "Author" "Antmicro"
			(at 247.65 50.8 0)
			(effects
				(font
					(size 1.27 1.27)
					(thickness 0.15)
				)
				(justify left bottom)
				(hide yes)
			)
		)
		(property "Val" "1k"
			(at 220.98 69.85 90)
			(effects
				(font
					(size 1.27 1.27)
					(thickness 0.15)
				)
				(justify right)
			)
		)
		(property "Tolerance" "1%"
			(at 229.87 50.8 0)
			(effects
				(font
					(size 1.27 1.27)
				)
				(justify left bottom)
				(hide yes)
			)
		)
		(pin "1"
		)
		(pin "2"
		)
		(instances
			(project ""
				(path ""
					(reference "R37")
					(unit 1)
				)
			)
		)
	)
	(symbol
		(lib_id "antmicroTVSDiodes:TPD2E2U06_SC70")
		(at 50.8 82.55 0)
		(unit 1)
		(exclude_from_sim no)
		(in_bom yes)
		(on_board yes)
		(dnp no)
		(property "Reference" "D6"
			(at 59.182 83.82 0)
			(effects
				(font
					(size 1.27 1.27)
					(thickness 0.15)
				)
				(justify left)
			)
		)
		(property "Value" "TPD2E2U06_SC70"
			(at 63.5 85.09 0)
			(effects
				(font
					(size 1.27 1.27)
					(thickness 0.15)
				)
				(justify left bottom)
				(hide yes)
			)
		)
		(property "Footprint" "antmicro-footprints:SC70-3"
			(at 63.5 87.63 0)
			(effects
				(font
					(size 1.27 1.27)
					(thickness 0.15)
				)
				(justify left bottom)
				(hide yes)
			)
		)
		(property "Datasheet" "https://www.ti.com/lit/ds/symlink/tpd2e2u06.pdf?ts=1706006131823&ref_url=https%253A%252F%252Fwww.ti.com%252Finterface%252Fdiodes%252Fesd-protection-diodes%252Fproducts.html"
			(at 63.5 90.17 0)
			(effects
				(font
					(size 1.27 1.27)
					(thickness 0.15)
				)
				(justify left bottom)
				(hide yes)
			)
		)
		(property "Description" "TVS diode array, 15 kV, SC70, 5.5V, 1.5 pF"
			(at 50.8 82.55 0)
			(effects
				(font
					(size 1.27 1.27)
				)
				(hide yes)
			)
		)
		(property "MPN" "TPD2E2U06DCKR"
			(at 59.182 86.36 0)
			(effects
				(font
					(size 1.27 1.27)
					(thickness 0.15)
				)
				(justify left)
			)
		)
		(property "Manufacturer" "Texas Instruments"
			(at 63.5 92.71 0)
			(effects
				(font
					(size 1.27 1.27)
					(thickness 0.15)
				)
				(justify left bottom)
				(hide yes)
			)
		)
		(property "Author" "Antmicro"
			(at 63.5 95.25 0)
			(effects
				(font
					(size 1.27 1.27)
					(thickness 0.15)
				)
				(justify left bottom)
				(hide yes)
			)
		)
		(property "License" "Apache-2.0"
			(at 63.5 97.79 0)
			(effects
				(font
					(size 1.27 1.27)
					(thickness 0.15)
				)
				(justify left bottom)
				(hide yes)
			)
		)
		(pin "2"
		)
		(pin "3"
		)
		(pin "1"
		)
		(instances
			(project ""
				(path ""
					(reference "D6")
					(unit 1)
				)
			)
		)
	)
	(symbol
		(lib_id "antmicropower:GND")
		(at 125.73 203.2 0)
		(unit 1)
		(exclude_from_sim no)
		(in_bom yes)
		(on_board yes)
		(dnp no)
		(property "Reference" "#PWR069"
			(at 125.73 203.2 0)
			(effects
				(font
					(size 1.27 1.27)
				)
				(justify left)
				(hide yes)
			)
		)
		(property "Value" "GND"
			(at 125.73 207.01 0)
			(effects
				(font
					(size 1.27 1.27)
				)
			)
		)
		(property "Footprint" ""
			(at 125.73 203.2 0)
			(effects
				(font
					(size 1.27 1.27)
					(thickness 0.15)
				)
				(justify left bottom)
				(hide yes)
			)
		)
		(property "Datasheet" ""
			(at 125.73 203.2 0)
			(effects
				(font
					(size 1.27 1.27)
					(thickness 0.15)
				)
				(justify left bottom)
				(hide yes)
			)
		)
		(property "Description" ""
			(at 125.73 203.2 0)
			(effects
				(font
					(size 1.27 1.27)
				)
				(hide yes)
			)
		)
		(property "Author" "Antmicro"
			(at 134.62 210.82 0)
			(effects
				(font
					(size 1.27 1.27)
					(thickness 0.15)
				)
				(justify left bottom)
				(hide yes)
			)
		)
		(property "License" "Apache-2.0"
			(at 134.62 213.36 0)
			(effects
				(font
					(size 1.27 1.27)
					(thickness 0.15)
				)
				(justify left bottom)
				(hide yes)
			)
		)
		(pin "1"
		)
		(instances
			(project "oculink-to-pcie-adapter"
				(path ""
					(reference "#PWR069")
					(unit 1)
				)
			)
		)
	)
	(symbol
		(lib_id "antmicropower:PWR_FLAG")
		(at 97.79 60.96 0)
		(unit 1)
		(exclude_from_sim no)
		(in_bom yes)
		(on_board yes)
		(dnp no)
		(property "Reference" "#FLG05"
			(at 97.79 59.055 0)
			(effects
				(font
					(size 1.27 1.27)
				)
				(hide yes)
			)
		)
		(property "Value" "PWR_FLAG"
			(at 97.79 57.15 0)
			(effects
				(font
					(size 1.27 1.27)
				)
			)
		)
		(property "Footprint" ""
			(at 97.79 60.96 0)
			(effects
				(font
					(size 1.27 1.27)
				)
				(hide yes)
			)
		)
		(property "Datasheet" ""
			(at 97.79 60.96 0)
			(effects
				(font
					(size 1.27 1.27)
				)
				(hide yes)
			)
		)
		(property "Description" ""
			(at 97.79 60.96 0)
			(effects
				(font
					(size 1.27 1.27)
				)
				(hide yes)
			)
		)
		(pin "1"
		)
		(instances
			(project "oculink-to-pcie-adapter"
				(path ""
					(reference "#FLG05")
					(unit 1)
				)
			)
		)
	)
	(symbol
		(lib_id "antmicropower:GND")
		(at 278.13 237.49 0)
		(unit 1)
		(exclude_from_sim no)
		(in_bom yes)
		(on_board yes)
		(dnp no)
		(property "Reference" "#PWR042"
			(at 278.13 237.49 0)
			(effects
				(font
					(size 1.27 1.27)
				)
				(justify left)
				(hide yes)
			)
		)
		(property "Value" "GND"
			(at 278.13 241.3 0)
			(effects
				(font
					(size 1.27 1.27)
				)
			)
		)
		(property "Footprint" ""
			(at 278.13 237.49 0)
			(effects
				(font
					(size 1.27 1.27)
					(thickness 0.15)
				)
				(justify left bottom)
				(hide yes)
			)
		)
		(property "Datasheet" ""
			(at 278.13 237.49 0)
			(effects
				(font
					(size 1.27 1.27)
					(thickness 0.15)
				)
				(justify left bottom)
				(hide yes)
			)
		)
		(property "Description" ""
			(at 278.13 237.49 0)
			(effects
				(font
					(size 1.27 1.27)
				)
				(hide yes)
			)
		)
		(property "Author" "Antmicro"
			(at 287.02 245.11 0)
			(effects
				(font
					(size 1.27 1.27)
					(thickness 0.15)
				)
				(justify left bottom)
				(hide yes)
			)
		)
		(property "License" "Apache-2.0"
			(at 287.02 247.65 0)
			(effects
				(font
					(size 1.27 1.27)
					(thickness 0.15)
				)
				(justify left bottom)
				(hide yes)
			)
		)
		(pin "1"
		)
		(instances
			(project "oculink-to-pcie-adapter"
				(path ""
					(reference "#PWR042")
					(unit 1)
				)
			)
		)
	)
	(symbol
		(lib_id "antmicroResistors0402:R_1k_0402")
		(at 381 96.52 90)
		(unit 1)
		(exclude_from_sim no)
		(in_bom yes)
		(on_board yes)
		(dnp no)
		(property "Reference" "R25"
			(at 382.27 92.71 90)
			(effects
				(font
					(size 1.27 1.27)
					(thickness 0.15)
				)
				(justify right)
			)
		)
		(property "Value" "R_1k_0402"
			(at 393.7 76.2 0)
			(effects
				(font
					(size 1.27 1.27)
					(thickness 0.15)
				)
				(justify left bottom)
				(hide yes)
			)
		)
		(property "Footprint" "antmicro-footprints:R_0402_1005Metric"
			(at 396.24 76.2 0)
			(effects
				(font
					(size 1.27 1.27)
					(thickness 0.15)
				)
				(justify left bottom)
				(hide yes)
			)
		)
		(property "Datasheet" "https://www.bourns.com/docs/product-datasheets/cr.pdf"
			(at 398.78 76.2 0)
			(effects
				(font
					(size 1.27 1.27)
					(thickness 0.15)
				)
				(justify left bottom)
				(hide yes)
			)
		)
		(property "Description" "SMD Chip Resistor, 1 kohm, ± 1%, 63 mW, 0402 [1005 Metric], Thick Film, General Purpose"
			(at 381 96.52 0)
			(effects
				(font
					(size 1.27 1.27)
				)
				(hide yes)
			)
		)
		(property "MPN" "CR0402-FX-1001GLF"
			(at 401.32 76.2 0)
			(effects
				(font
					(size 1.27 1.27)
					(thickness 0.15)
				)
				(justify left bottom)
				(hide yes)
			)
		)
		(property "Manufacturer" "Bourns"
			(at 403.86 76.2 0)
			(effects
				(font
					(size 1.27 1.27)
					(thickness 0.15)
				)
				(justify left bottom)
				(hide yes)
			)
		)
		(property "License" "Apache-2.0"
			(at 406.4 76.2 0)
			(effects
				(font
					(size 1.27 1.27)
					(thickness 0.15)
				)
				(justify left bottom)
				(hide yes)
			)
		)
		(property "Author" "Antmicro"
			(at 408.94 76.2 0)
			(effects
				(font
					(size 1.27 1.27)
					(thickness 0.15)
				)
				(justify left bottom)
				(hide yes)
			)
		)
		(property "Val" "1k"
			(at 382.27 95.25 90)
			(effects
				(font
					(size 1.27 1.27)
					(thickness 0.15)
				)
				(justify right)
			)
		)
		(property "Tolerance" "1%"
			(at 391.16 76.2 0)
			(effects
				(font
					(size 1.27 1.27)
				)
				(justify left bottom)
				(hide yes)
			)
		)
		(pin "2"
		)
		(pin "1"
		)
		(instances
			(project "oculink-to-pcie-adapter"
				(path ""
					(reference "R25")
					(unit 1)
				)
			)
		)
	)
	(symbol
		(lib_id "antmicroResistors0402:R_1k_0402")
		(at 342.9 106.68 90)
		(unit 1)
		(exclude_from_sim no)
		(in_bom yes)
		(on_board yes)
		(dnp no)
		(property "Reference" "R21"
			(at 344.17 102.87 90)
			(effects
				(font
					(size 1.27 1.27)
					(thickness 0.15)
				)
				(justify right)
			)
		)
		(property "Value" "R_1k_0402"
			(at 355.6 86.36 0)
			(effects
				(font
					(size 1.27 1.27)
					(thickness 0.15)
				)
				(justify left bottom)
				(hide yes)
			)
		)
		(property "Footprint" "antmicro-footprints:R_0402_1005Metric"
			(at 358.14 86.36 0)
			(effects
				(font
					(size 1.27 1.27)
					(thickness 0.15)
				)
				(justify left bottom)
				(hide yes)
			)
		)
		(property "Datasheet" "https://www.bourns.com/docs/product-datasheets/cr.pdf"
			(at 360.68 86.36 0)
			(effects
				(font
					(size 1.27 1.27)
					(thickness 0.15)
				)
				(justify left bottom)
				(hide yes)
			)
		)
		(property "Description" "SMD Chip Resistor, 1 kohm, ± 1%, 63 mW, 0402 [1005 Metric], Thick Film, General Purpose"
			(at 342.9 106.68 0)
			(effects
				(font
					(size 1.27 1.27)
				)
				(hide yes)
			)
		)
		(property "MPN" "CR0402-FX-1001GLF"
			(at 363.22 86.36 0)
			(effects
				(font
					(size 1.27 1.27)
					(thickness 0.15)
				)
				(justify left bottom)
				(hide yes)
			)
		)
		(property "Manufacturer" "Bourns"
			(at 365.76 86.36 0)
			(effects
				(font
					(size 1.27 1.27)
					(thickness 0.15)
				)
				(justify left bottom)
				(hide yes)
			)
		)
		(property "License" "Apache-2.0"
			(at 368.3 86.36 0)
			(effects
				(font
					(size 1.27 1.27)
					(thickness 0.15)
				)
				(justify left bottom)
				(hide yes)
			)
		)
		(property "Author" "Antmicro"
			(at 370.84 86.36 0)
			(effects
				(font
					(size 1.27 1.27)
					(thickness 0.15)
				)
				(justify left bottom)
				(hide yes)
			)
		)
		(property "Val" "1k"
			(at 344.17 105.41 90)
			(effects
				(font
					(size 1.27 1.27)
					(thickness 0.15)
				)
				(justify right)
			)
		)
		(property "Tolerance" "1%"
			(at 353.06 86.36 0)
			(effects
				(font
					(size 1.27 1.27)
				)
				(justify left bottom)
				(hide yes)
			)
		)
		(pin "2"
		)
		(pin "1"
		)
		(instances
			(project "oculink-to-pcie-adapter"
				(path ""
					(reference "R21")
					(unit 1)
				)
			)
		)
	)
	(symbol
		(lib_id "antmicropower:GND")
		(at 259.08 134.62 0)
		(mirror y)
		(unit 1)
		(exclude_from_sim no)
		(in_bom yes)
		(on_board yes)
		(dnp no)
		(property "Reference" "#PWR047"
			(at 250.19 137.16 0)
			(effects
				(font
					(size 1.27 1.27)
					(thickness 0.15)
				)
				(justify left bottom)
				(hide yes)
			)
		)
		(property "Value" "GND"
			(at 259.08 138.43 0)
			(effects
				(font
					(size 1.27 1.27)
					(thickness 0.15)
				)
			)
		)
		(property "Footprint" ""
			(at 250.19 142.24 0)
			(effects
				(font
					(size 1.27 1.27)
					(thickness 0.15)
				)
				(justify left bottom)
				(hide yes)
			)
		)
		(property "Datasheet" ""
			(at 250.19 147.32 0)
			(effects
				(font
					(size 1.27 1.27)
					(thickness 0.15)
				)
				(justify left bottom)
				(hide yes)
			)
		)
		(property "Description" ""
			(at 259.08 134.62 0)
			(effects
				(font
					(size 1.27 1.27)
				)
				(hide yes)
			)
		)
		(property "Author" "Antmicro"
			(at 250.19 142.24 0)
			(effects
				(font
					(size 1.27 1.27)
					(thickness 0.15)
				)
				(justify left bottom)
				(hide yes)
			)
		)
		(property "License" "Apache-2.0"
			(at 250.19 144.78 0)
			(effects
				(font
					(size 1.27 1.27)
					(thickness 0.15)
				)
				(justify left bottom)
				(hide yes)
			)
		)
		(pin "1"
		)
		(instances
			(project "oculink-to-pcie-adapter"
				(path ""
					(reference "#PWR047")
					(unit 1)
				)
			)
		)
	)
	(symbol
		(lib_id "antmicroResistors0402:R_140k_0.1%_0402")
		(at 242.57 205.74 90)
		(unit 1)
		(exclude_from_sim no)
		(in_bom yes)
		(on_board yes)
		(dnp no)
		(property "Reference" "R40"
			(at 243.84 201.93 90)
			(effects
				(font
					(size 1.27 1.27)
					(thickness 0.15)
				)
				(justify right)
			)
		)
		(property "Value" "R_140k_0.1%_0402"
			(at 255.27 185.42 0)
			(effects
				(font
					(size 1.27 1.27)
					(thickness 0.15)
				)
				(justify left bottom)
				(hide yes)
			)
		)
		(property "Footprint" "antmicro-footprints:R_0402_1005Metric"
			(at 257.81 185.42 0)
			(effects
				(font
					(size 1.27 1.27)
					(thickness 0.15)
				)
				(justify left bottom)
				(hide yes)
			)
		)
		(property "Datasheet" "https://www.vishay.com/docs/28758/tnpw_e3.pdf"
			(at 260.35 185.42 0)
			(effects
				(font
					(size 1.27 1.27)
					(thickness 0.15)
				)
				(justify left bottom)
				(hide yes)
			)
		)
		(property "Description" "SMD Chip Resistor, Ceramic, 140 kohm, ± 0.1%, 62.5 mW, 0402 [1005 Metric], Thin Film, Precision resistors"
			(at 242.57 205.74 0)
			(effects
				(font
					(size 1.27 1.27)
				)
				(hide yes)
			)
		)
		(property "MPN" "RT0402BRD07140KL"
			(at 252.73 175.26 0)
			(effects
				(font
					(size 1.27 1.27)
					(thickness 0.15)
				)
				(justify left bottom)
				(hide yes)
			)
		)
		(property "Val" "140k"
			(at 243.84 204.47 90)
			(effects
				(font
					(size 1.27 1.27)
					(thickness 0.15)
				)
				(justify right)
			)
		)
		(property "Manufacturer" "YAGEO"
			(at 265.43 185.42 0)
			(effects
				(font
					(size 1.27 1.27)
					(thickness 0.15)
				)
				(justify left bottom)
				(hide yes)
			)
		)
		(property "Tolerance" "0.1%"
			(at 248.92 182.88 0)
			(effects
				(font
					(size 1.27 1.27)
					(thickness 0.15)
				)
				(justify left bottom)
				(hide yes)
			)
		)
		(property "License" "Apache-2.0"
			(at 267.97 185.42 0)
			(effects
				(font
					(size 1.27 1.27)
					(thickness 0.15)
				)
				(justify left bottom)
				(hide yes)
			)
		)
		(property "Author" "Antmicro"
			(at 270.51 185.42 0)
			(effects
				(font
					(size 1.27 1.27)
					(thickness 0.15)
				)
				(justify left bottom)
				(hide yes)
			)
		)
		(pin "2"
		)
		(pin "1"
		)
		(instances
			(project "oculink-to-pcie-adapter"
				(path ""
					(reference "R40")
					(unit 1)
				)
			)
		)
	)
	(symbol
		(lib_id "antmicroResistors0402:R_2k_0402")
		(at 125.73 228.6 270)
		(unit 1)
		(exclude_from_sim no)
		(in_bom yes)
		(on_board yes)
		(dnp no)
		(property "Reference" "R23"
			(at 127 229.8699 90)
			(effects
				(font
					(size 1.27 1.27)
				)
				(justify left)
			)
		)
		(property "Value" "R_2k_0402"
			(at 121.92 228.6 0)
			(effects
				(font
					(size 1.27 1.27)
				)
				(justify left)
				(hide yes)
			)
		)
		(property "Footprint" "antmicro-footprints:R_0402_1005Metric"
			(at 130.81 233.68 0)
			(effects
				(font
					(size 1.27 1.27)
					(thickness 0.15)
				)
				(justify left bottom)
				(hide yes)
			)
		)
		(property "Datasheet" "https://www.bourns.com/docs/product-datasheets/cr.pdf"
			(at 125.73 228.6 0)
			(effects
				(font
					(size 1.27 1.27)
					(thickness 0.15)
				)
				(justify left bottom)
				(hide yes)
			)
		)
		(property "Description" "SMD Chip Resistor, 2 kohm, ± 1%, 62.5 mW, 0402 [1005 Metric], Thick Film, General Purpose"
			(at 125.73 228.6 0)
			(effects
				(font
					(size 1.27 1.27)
				)
				(hide yes)
			)
		)
		(property "Manufacturer" "Bourns"
			(at 135.89 233.68 0)
			(effects
				(font
					(size 1.27 1.27)
					(thickness 0.15)
				)
				(justify left bottom)
				(hide yes)
			)
		)
		(property "MPN" "CR0402-FX-2001GLF"
			(at 133.35 233.68 0)
			(effects
				(font
					(size 1.27 1.27)
					(thickness 0.15)
				)
				(justify left bottom)
				(hide yes)
			)
		)
		(property "Val" "2k"
			(at 127 232.41 90)
			(effects
				(font
					(size 1.27 1.27)
					(thickness 0.15)
				)
				(justify left)
			)
		)
		(property "License" "Apache-2.0"
			(at 100.33 248.92 0)
			(effects
				(font
					(size 1.27 1.27)
					(thickness 0.15)
				)
				(justify left bottom)
				(hide yes)
			)
		)
		(property "Author" "Antmicro"
			(at 97.79 248.92 0)
			(effects
				(font
					(size 1.27 1.27)
					(thickness 0.15)
				)
				(justify left bottom)
				(hide yes)
			)
		)
		(property "Tolerance" "1%"
			(at 115.57 248.92 0)
			(effects
				(font
					(size 1.27 1.27)
				)
				(justify left bottom)
				(hide yes)
			)
		)
		(pin "1"
		)
		(pin "2"
		)
		(instances
			(project "oculink-to-pcie-adapter"
				(path ""
					(reference "R23")
					(unit 1)
				)
			)
		)
	)
	(symbol
		(lib_id "antmicropower:GND")
		(at 105.41 203.2 0)
		(unit 1)
		(exclude_from_sim no)
		(in_bom yes)
		(on_board yes)
		(dnp no)
		(property "Reference" "#PWR091"
			(at 105.41 203.2 0)
			(effects
				(font
					(size 1.27 1.27)
				)
				(justify left)
				(hide yes)
			)
		)
		(property "Value" "GND"
			(at 105.41 207.01 0)
			(effects
				(font
					(size 1.27 1.27)
				)
			)
		)
		(property "Footprint" ""
			(at 105.41 203.2 0)
			(effects
				(font
					(size 1.27 1.27)
					(thickness 0.15)
				)
				(justify left bottom)
				(hide yes)
			)
		)
		(property "Datasheet" ""
			(at 105.41 203.2 0)
			(effects
				(font
					(size 1.27 1.27)
					(thickness 0.15)
				)
				(justify left bottom)
				(hide yes)
			)
		)
		(property "Description" ""
			(at 105.41 203.2 0)
			(effects
				(font
					(size 1.27 1.27)
				)
				(hide yes)
			)
		)
		(property "Author" "Antmicro"
			(at 114.3 210.82 0)
			(effects
				(font
					(size 1.27 1.27)
					(thickness 0.15)
				)
				(justify left bottom)
				(hide yes)
			)
		)
		(property "License" "Apache-2.0"
			(at 114.3 213.36 0)
			(effects
				(font
					(size 1.27 1.27)
					(thickness 0.15)
				)
				(justify left bottom)
				(hide yes)
			)
		)
		(pin "1"
		)
		(instances
			(project "oculink-to-pcie-adapter"
				(path ""
					(reference "#PWR091")
					(unit 1)
				)
			)
		)
	)
	(symbol
		(lib_id "antmicropower:GND")
		(at 381 71.12 0)
		(unit 1)
		(exclude_from_sim no)
		(in_bom yes)
		(on_board yes)
		(dnp no)
		(property "Reference" "#PWR044"
			(at 389.89 73.66 0)
			(effects
				(font
					(size 1.27 1.27)
					(thickness 0.15)
				)
				(justify left bottom)
				(hide yes)
			)
		)
		(property "Value" "GND"
			(at 381 74.93 0)
			(effects
				(font
					(size 1.27 1.27)
					(thickness 0.15)
				)
			)
		)
		(property "Footprint" ""
			(at 389.89 78.74 0)
			(effects
				(font
					(size 1.27 1.27)
					(thickness 0.15)
				)
				(justify left bottom)
				(hide yes)
			)
		)
		(property "Datasheet" ""
			(at 389.89 83.82 0)
			(effects
				(font
					(size 1.27 1.27)
					(thickness 0.15)
				)
				(justify left bottom)
				(hide yes)
			)
		)
		(property "Description" ""
			(at 381 71.12 0)
			(effects
				(font
					(size 1.27 1.27)
				)
				(hide yes)
			)
		)
		(property "Author" "Antmicro"
			(at 389.89 78.74 0)
			(effects
				(font
					(size 1.27 1.27)
					(thickness 0.15)
				)
				(justify left bottom)
				(hide yes)
			)
		)
		(property "License" "Apache-2.0"
			(at 389.89 81.28 0)
			(effects
				(font
					(size 1.27 1.27)
					(thickness 0.15)
				)
				(justify left bottom)
				(hide yes)
			)
		)
		(pin "1"
		)
		(instances
			(project "oculink-to-pcie-adapter"
				(path ""
					(reference "#PWR044")
					(unit 1)
				)
			)
		)
	)
	(symbol
		(lib_id "antmicroInterfaceControllers:CYPD3177-24LQXQ")
		(at 175.26 73.66 0)
		(unit 1)
		(exclude_from_sim no)
		(in_bom yes)
		(on_board yes)
		(dnp no)
		(fields_autoplaced yes)
		(property "Reference" "U5"
			(at 191.77 66.04 0)
			(effects
				(font
					(size 1.27 1.27)
					(thickness 0.15)
				)
			)
		)
		(property "Value" "CYPD3177-24LQXQ"
			(at 223.52 81.28 0)
			(effects
				(font
					(size 1.27 1.27)
					(thickness 0.15)
				)
				(justify left bottom)
				(hide yes)
			)
		)
		(property "Footprint" "antmicro-footprints:QFN-24-1EP_4x4mm_P0.5mm_EP2.6x2.6mm"
			(at 223.52 83.82 0)
			(effects
				(font
					(size 1.27 1.27)
					(thickness 0.15)
				)
				(justify left bottom)
				(hide yes)
			)
		)
		(property "Datasheet" "https://www.infineon.com/dgdl/Infineon-EZ-PD_BCR_Datasheet_USB_Type-C_Port_Controller_for_Power_Sinks-DataSheet-v03_00-EN.pdf?fileId=8ac78c8c7d0d8da4017d0ee7ce9d70ad"
			(at 223.52 86.36 0)
			(effects
				(font
					(size 1.27 1.27)
					(thickness 0.15)
				)
				(justify left bottom)
				(hide yes)
			)
		)
		(property "Description" "USB Interface, USB Type-C and Power Delivery (PD) Controller, USB PD 3.0, 2.7 V, 5.5 V, QFN-EP"
			(at 175.26 73.66 0)
			(effects
				(font
					(size 1.27 1.27)
				)
				(hide yes)
			)
		)
		(property "MPN" "CYPD3177-24LQXQ"
			(at 191.77 68.58 0)
			(effects
				(font
					(size 1.27 1.27)
					(thickness 0.15)
				)
			)
		)
		(property "Manufacturer" "Infineon"
			(at 223.52 88.9 0)
			(effects
				(font
					(size 1.27 1.27)
					(thickness 0.15)
				)
				(justify left bottom)
				(hide yes)
			)
		)
		(property "Author" "Antmicro"
			(at 223.52 91.44 0)
			(effects
				(font
					(size 1.27 1.27)
					(thickness 0.15)
				)
				(justify left bottom)
				(hide yes)
			)
		)
		(property "License" "Apache-2.0"
			(at 223.52 93.98 0)
			(effects
				(font
					(size 1.27 1.27)
					(thickness 0.15)
				)
				(justify left bottom)
				(hide yes)
			)
		)
		(pin "10"
		)
		(pin "9"
		)
		(pin "18"
		)
		(pin "1"
		)
		(pin "21"
		)
		(pin "12"
		)
		(pin "4"
		)
		(pin "24"
		)
		(pin "19"
		)
		(pin "5"
		)
		(pin "20"
		)
		(pin "22"
		)
		(pin "2"
		)
		(pin "14"
		)
		(pin "23"
		)
		(pin "3"
		)
		(pin "25"
		)
		(pin "16"
		)
		(pin "8"
		)
		(pin "15"
		)
		(pin "17"
		)
		(pin "13"
		)
		(pin "7"
		)
		(pin "6"
		)
		(pin "11"
		)
		(instances
			(project ""
				(path ""
					(reference "U5")
					(unit 1)
				)
			)
		)
	)
	(symbol
		(lib_id "antmicropower:GND")
		(at 143.51 203.2 0)
		(unit 1)
		(exclude_from_sim no)
		(in_bom yes)
		(on_board yes)
		(dnp no)
		(property "Reference" "#PWR089"
			(at 143.51 203.2 0)
			(effects
				(font
					(size 1.27 1.27)
				)
				(justify left)
				(hide yes)
			)
		)
		(property "Value" "GND"
			(at 143.51 207.01 0)
			(effects
				(font
					(size 1.27 1.27)
				)
			)
		)
		(property "Footprint" ""
			(at 143.51 203.2 0)
			(effects
				(font
					(size 1.27 1.27)
					(thickness 0.15)
				)
				(justify left bottom)
				(hide yes)
			)
		)
		(property "Datasheet" ""
			(at 143.51 203.2 0)
			(effects
				(font
					(size 1.27 1.27)
					(thickness 0.15)
				)
				(justify left bottom)
				(hide yes)
			)
		)
		(property "Description" ""
			(at 143.51 203.2 0)
			(effects
				(font
					(size 1.27 1.27)
				)
				(hide yes)
			)
		)
		(property "Author" "Antmicro"
			(at 152.4 210.82 0)
			(effects
				(font
					(size 1.27 1.27)
					(thickness 0.15)
				)
				(justify left bottom)
				(hide yes)
			)
		)
		(property "License" "Apache-2.0"
			(at 152.4 213.36 0)
			(effects
				(font
					(size 1.27 1.27)
					(thickness 0.15)
				)
				(justify left bottom)
				(hide yes)
			)
		)
		(pin "1"
		)
		(instances
			(project "oculink-to-pcie-adapter"
				(path ""
					(reference "#PWR089")
					(unit 1)
				)
			)
		)
	)
	(symbol
		(lib_id "antmicropower:GND")
		(at 116.84 237.49 0)
		(mirror y)
		(unit 1)
		(exclude_from_sim no)
		(in_bom yes)
		(on_board yes)
		(dnp no)
		(property "Reference" "#PWR059"
			(at 116.84 237.49 0)
			(effects
				(font
					(size 1.27 1.27)
				)
				(justify left)
				(hide yes)
			)
		)
		(property "Value" "GND"
			(at 116.84 241.935 0)
			(effects
				(font
					(size 1.27 1.27)
				)
			)
		)
		(property "Footprint" ""
			(at 116.84 237.49 0)
			(effects
				(font
					(size 1.27 1.27)
					(thickness 0.15)
				)
				(justify left bottom)
				(hide yes)
			)
		)
		(property "Datasheet" ""
			(at 116.84 237.49 0)
			(effects
				(font
					(size 1.27 1.27)
					(thickness 0.15)
				)
				(justify left bottom)
				(hide yes)
			)
		)
		(property "Description" ""
			(at 116.84 237.49 0)
			(effects
				(font
					(size 1.27 1.27)
				)
				(hide yes)
			)
		)
		(property "Author" "Antmicro"
			(at 107.95 245.11 0)
			(effects
				(font
					(size 1.27 1.27)
					(thickness 0.15)
				)
				(justify left bottom)
				(hide yes)
			)
		)
		(property "License" "Apache-2.0"
			(at 107.95 247.65 0)
			(effects
				(font
					(size 1.27 1.27)
					(thickness 0.15)
				)
				(justify left bottom)
				(hide yes)
			)
		)
		(pin "1"
		)
		(instances
			(project "oculink-to-pcie-adapter"
				(path ""
					(reference "#PWR059")
					(unit 1)
				)
			)
		)
	)
	(symbol
		(lib_id "antmicroCapacitorsmisc:C_10u_0805_35V")
		(at 125.73 201.93 90)
		(unit 1)
		(exclude_from_sim no)
		(in_bom yes)
		(on_board yes)
		(dnp no)
		(fields_autoplaced yes)
		(property "Reference" "C22"
			(at 128.27 198.1136 90)
			(effects
				(font
					(size 1.27 1.27)
					(thickness 0.15)
				)
				(justify right)
			)
		)
		(property "Value" "C_10u_0805_35V"
			(at 135.89 181.61 0)
			(effects
				(font
					(size 1.27 1.27)
					(thickness 0.15)
				)
				(justify left bottom)
				(hide yes)
			)
		)
		(property "Footprint" "antmicro-footprints:C_0805_2012Metric"
			(at 138.43 181.61 0)
			(effects
				(font
					(size 1.27 1.27)
					(thickness 0.15)
				)
				(justify left bottom)
				(hide yes)
			)
		)
		(property "Datasheet" "https://www.murata.com/products/productdetail?partno=GRM21BR6YA106KE43%23"
			(at 140.97 181.61 0)
			(effects
				(font
					(size 1.27 1.27)
					(thickness 0.15)
				)
				(justify left bottom)
				(hide yes)
			)
		)
		(property "Description" "SMD Multilayer Ceramic Capacitor, 10 µF, 35 V, 0805 [2012 Metric], ± 10%, X5R, GRM Series"
			(at 125.73 201.93 0)
			(effects
				(font
					(size 1.27 1.27)
				)
				(hide yes)
			)
		)
		(property "MPN" "GRM21BR6YA106KE43L"
			(at 143.51 181.61 0)
			(effects
				(font
					(size 1.27 1.27)
					(thickness 0.15)
				)
				(justify left bottom)
				(hide yes)
			)
		)
		(property "Manufacturer" "Murata"
			(at 146.05 181.61 0)
			(effects
				(font
					(size 1.27 1.27)
					(thickness 0.15)
				)
				(justify left bottom)
				(hide yes)
			)
		)
		(property "License" "Apache-2.0"
			(at 148.59 181.61 0)
			(effects
				(font
					(size 1.27 1.27)
					(thickness 0.15)
				)
				(justify left bottom)
				(hide yes)
			)
		)
		(property "Author" "Antmicro"
			(at 151.13 181.61 0)
			(effects
				(font
					(size 1.27 1.27)
					(thickness 0.15)
				)
				(justify left bottom)
				(hide yes)
			)
		)
		(property "Val" "10u"
			(at 128.27 200.6536 90)
			(effects
				(font
					(size 1.27 1.27)
					(thickness 0.15)
				)
				(justify right)
			)
		)
		(property "Voltage" "35V"
			(at 153.67 181.61 0)
			(effects
				(font
					(size 1.27 1.27)
				)
				(justify left bottom)
				(hide yes)
			)
		)
		(property "Dielectric" ""
			(at 156.21 181.61 0)
			(effects
				(font
					(size 1.27 1.27)
				)
				(justify left bottom)
				(hide yes)
			)
		)
		(property "Public" "False"
			(at 158.75 181.61 0)
			(effects
				(font
					(size 1.27 1.27)
				)
				(justify left bottom)
				(hide yes)
			)
		)
		(pin "2"
		)
		(pin "1"
		)
		(instances
			(project "oculink-to-pcie-adapter"
				(path ""
					(reference "C22")
					(unit 1)
				)
			)
		)
	)
	(symbol
		(lib_id "antmicroCapacitors0402:C_1u_25V_0402")
		(at 107.95 233.68 90)
		(unit 1)
		(exclude_from_sim no)
		(in_bom yes)
		(on_board yes)
		(dnp no)
		(property "Reference" "C20"
			(at 110.236 229.87 90)
			(effects
				(font
					(size 1.27 1.27)
					(thickness 0.15)
				)
				(justify right)
			)
		)
		(property "Value" "C_1u_25V_0402"
			(at 118.11 213.36 0)
			(effects
				(font
					(size 1.27 1.27)
					(thickness 0.15)
				)
				(justify left bottom)
				(hide yes)
			)
		)
		(property "Footprint" "antmicro-footprints:C_0402_1005Metric"
			(at 120.65 213.36 0)
			(effects
				(font
					(size 1.27 1.27)
					(thickness 0.15)
				)
				(justify left bottom)
				(hide yes)
			)
		)
		(property "Datasheet" "https://www.murata.com/products/productdetail?partno=GRM155R61E105KE11%23"
			(at 123.19 213.36 0)
			(effects
				(font
					(size 1.27 1.27)
					(thickness 0.15)
				)
				(justify left bottom)
				(hide yes)
			)
		)
		(property "Description" "SMD Multilayer Ceramic Capacitor, 1 µF, 25 V, 0402 [1005 Metric], ± 10%, X5R, GRM Series"
			(at 107.95 233.68 0)
			(effects
				(font
					(size 1.27 1.27)
				)
				(hide yes)
			)
		)
		(property "MPN" "GRM155R61E105KE11J"
			(at 125.73 213.36 0)
			(effects
				(font
					(size 1.27 1.27)
					(thickness 0.15)
				)
				(justify left bottom)
				(hide yes)
			)
		)
		(property "Manufacturer" "Murata"
			(at 128.27 213.36 0)
			(effects
				(font
					(size 1.27 1.27)
					(thickness 0.15)
				)
				(justify left bottom)
				(hide yes)
			)
		)
		(property "License" "Apache-2.0"
			(at 130.81 213.36 0)
			(effects
				(font
					(size 1.27 1.27)
					(thickness 0.15)
				)
				(justify left bottom)
				(hide yes)
			)
		)
		(property "Author" "Antmicro"
			(at 133.35 213.36 0)
			(effects
				(font
					(size 1.27 1.27)
					(thickness 0.15)
				)
				(justify left bottom)
				(hide yes)
			)
		)
		(property "Val" "1u"
			(at 110.236 232.41 90)
			(effects
				(font
					(size 1.27 1.27)
					(thickness 0.15)
				)
				(justify right)
			)
		)
		(property "Voltage" "25V"
			(at 135.89 213.36 0)
			(effects
				(font
					(size 1.27 1.27)
				)
				(justify left bottom)
				(hide yes)
			)
		)
		(property "Dielectric" "X5R"
			(at 138.43 213.36 0)
			(effects
				(font
					(size 1.27 1.27)
				)
				(justify left bottom)
				(hide yes)
			)
		)
		(pin "2"
		)
		(pin "1"
		)
		(instances
			(project "oculink-to-pcie-adapter"
				(path ""
					(reference "C20")
					(unit 1)
				)
			)
		)
	)
	(symbol
		(lib_id "antmicropower:GND")
		(at 107.95 237.49 0)
		(mirror y)
		(unit 1)
		(exclude_from_sim no)
		(in_bom yes)
		(on_board yes)
		(dnp no)
		(property "Reference" "#PWR058"
			(at 107.95 237.49 0)
			(effects
				(font
					(size 1.27 1.27)
				)
				(justify left)
				(hide yes)
			)
		)
		(property "Value" "GND"
			(at 107.95 241.935 0)
			(effects
				(font
					(size 1.27 1.27)
				)
			)
		)
		(property "Footprint" ""
			(at 107.95 237.49 0)
			(effects
				(font
					(size 1.27 1.27)
					(thickness 0.15)
				)
				(justify left bottom)
				(hide yes)
			)
		)
		(property "Datasheet" ""
			(at 107.95 237.49 0)
			(effects
				(font
					(size 1.27 1.27)
					(thickness 0.15)
				)
				(justify left bottom)
				(hide yes)
			)
		)
		(property "Description" ""
			(at 107.95 237.49 0)
			(effects
				(font
					(size 1.27 1.27)
				)
				(hide yes)
			)
		)
		(property "Author" "Antmicro"
			(at 99.06 245.11 0)
			(effects
				(font
					(size 1.27 1.27)
					(thickness 0.15)
				)
				(justify left bottom)
				(hide yes)
			)
		)
		(property "License" "Apache-2.0"
			(at 99.06 247.65 0)
			(effects
				(font
					(size 1.27 1.27)
					(thickness 0.15)
				)
				(justify left bottom)
				(hide yes)
			)
		)
		(pin "1"
		)
		(instances
			(project "oculink-to-pcie-adapter"
				(path ""
					(reference "#PWR058")
					(unit 1)
				)
			)
		)
	)
	(symbol
		(lib_id "antmicropower:GND")
		(at 172.72 119.38 0)
		(unit 1)
		(exclude_from_sim no)
		(in_bom yes)
		(on_board yes)
		(dnp no)
		(property "Reference" "#PWR0102"
			(at 181.61 121.92 0)
			(effects
				(font
					(size 1.27 1.27)
					(thickness 0.15)
				)
				(justify left bottom)
				(hide yes)
			)
		)
		(property "Value" "GND"
			(at 172.72 123.19 0)
			(effects
				(font
					(size 1.27 1.27)
					(thickness 0.15)
				)
			)
		)
		(property "Footprint" ""
			(at 181.61 127 0)
			(effects
				(font
					(size 1.27 1.27)
					(thickness 0.15)
				)
				(justify left bottom)
				(hide yes)
			)
		)
		(property "Datasheet" ""
			(at 181.61 132.08 0)
			(effects
				(font
					(size 1.27 1.27)
					(thickness 0.15)
				)
				(justify left bottom)
				(hide yes)
			)
		)
		(property "Description" ""
			(at 172.72 119.38 0)
			(effects
				(font
					(size 1.27 1.27)
				)
				(hide yes)
			)
		)
		(property "Author" "Antmicro"
			(at 181.61 127 0)
			(effects
				(font
					(size 1.27 1.27)
					(thickness 0.15)
				)
				(justify left bottom)
				(hide yes)
			)
		)
		(property "License" "Apache-2.0"
			(at 181.61 129.54 0)
			(effects
				(font
					(size 1.27 1.27)
					(thickness 0.15)
				)
				(justify left bottom)
				(hide yes)
			)
		)
		(pin "1"
		)
		(instances
			(project "oculink-to-pcie-adapter"
				(path ""
					(reference "#PWR0102")
					(unit 1)
				)
			)
		)
	)
	(symbol
		(lib_id "antmicropower:GND")
		(at 133.35 237.49 0)
		(unit 1)
		(exclude_from_sim no)
		(in_bom yes)
		(on_board yes)
		(dnp no)
		(property "Reference" "#PWR070"
			(at 133.35 237.49 0)
			(effects
				(font
					(size 1.27 1.27)
				)
				(justify left)
				(hide yes)
			)
		)
		(property "Value" "GND"
			(at 133.35 241.3 0)
			(effects
				(font
					(size 1.27 1.27)
				)
			)
		)
		(property "Footprint" ""
			(at 133.35 237.49 0)
			(effects
				(font
					(size 1.27 1.27)
					(thickness 0.15)
				)
				(justify left bottom)
				(hide yes)
			)
		)
		(property "Datasheet" ""
			(at 133.35 237.49 0)
			(effects
				(font
					(size 1.27 1.27)
					(thickness 0.15)
				)
				(justify left bottom)
				(hide yes)
			)
		)
		(property "Description" ""
			(at 133.35 237.49 0)
			(effects
				(font
					(size 1.27 1.27)
				)
				(hide yes)
			)
		)
		(property "Author" "Antmicro"
			(at 142.24 245.11 0)
			(effects
				(font
					(size 1.27 1.27)
					(thickness 0.15)
				)
				(justify left bottom)
				(hide yes)
			)
		)
		(property "License" "Apache-2.0"
			(at 142.24 247.65 0)
			(effects
				(font
					(size 1.27 1.27)
					(thickness 0.15)
				)
				(justify left bottom)
				(hide yes)
			)
		)
		(pin "1"
		)
		(instances
			(project "oculink-to-pcie-adapter"
				(path ""
					(reference "#PWR070")
					(unit 1)
				)
			)
		)
	)
	(symbol
		(lib_id "antmicropower:GND")
		(at 248.92 134.62 0)
		(mirror y)
		(unit 1)
		(exclude_from_sim no)
		(in_bom yes)
		(on_board yes)
		(dnp no)
		(property "Reference" "#PWR046"
			(at 240.03 137.16 0)
			(effects
				(font
					(size 1.27 1.27)
					(thickness 0.15)
				)
				(justify left bottom)
				(hide yes)
			)
		)
		(property "Value" "GND"
			(at 248.92 138.43 0)
			(effects
				(font
					(size 1.27 1.27)
					(thickness 0.15)
				)
			)
		)
		(property "Footprint" ""
			(at 240.03 142.24 0)
			(effects
				(font
					(size 1.27 1.27)
					(thickness 0.15)
				)
				(justify left bottom)
				(hide yes)
			)
		)
		(property "Datasheet" ""
			(at 240.03 147.32 0)
			(effects
				(font
					(size 1.27 1.27)
					(thickness 0.15)
				)
				(justify left bottom)
				(hide yes)
			)
		)
		(property "Description" ""
			(at 248.92 134.62 0)
			(effects
				(font
					(size 1.27 1.27)
				)
				(hide yes)
			)
		)
		(property "Author" "Antmicro"
			(at 240.03 142.24 0)
			(effects
				(font
					(size 1.27 1.27)
					(thickness 0.15)
				)
				(justify left bottom)
				(hide yes)
			)
		)
		(property "License" "Apache-2.0"
			(at 240.03 144.78 0)
			(effects
				(font
					(size 1.27 1.27)
					(thickness 0.15)
				)
				(justify left bottom)
				(hide yes)
			)
		)
		(pin "1"
		)
		(instances
			(project "oculink-to-pcie-adapter"
				(path ""
					(reference "#PWR046")
					(unit 1)
				)
			)
		)
	)
	(symbol
		(lib_id "antmicroCapacitors0402:C_100n_0402")
		(at 140.97 116.84 90)
		(unit 1)
		(exclude_from_sim no)
		(in_bom yes)
		(on_board yes)
		(dnp no)
		(fields_autoplaced yes)
		(property "Reference" "C41"
			(at 143.51 113.0236 90)
			(effects
				(font
					(size 1.27 1.27)
					(thickness 0.15)
				)
				(justify right)
			)
		)
		(property "Value" "C_100n_0402"
			(at 151.13 96.52 0)
			(effects
				(font
					(size 1.27 1.27)
					(thickness 0.15)
				)
				(justify left bottom)
				(hide yes)
			)
		)
		(property "Footprint" "antmicro-footprints:C_0402_1005Metric"
			(at 153.67 96.52 0)
			(effects
				(font
					(size 1.27 1.27)
					(thickness 0.15)
				)
				(justify left bottom)
				(hide yes)
			)
		)
		(property "Datasheet" "https://www.murata.com/products/productdetail?partno=GRM155R61H104KE14%23"
			(at 156.21 96.52 0)
			(effects
				(font
					(size 1.27 1.27)
					(thickness 0.15)
				)
				(justify left bottom)
				(hide yes)
			)
		)
		(property "Description" "SMD Multilayer Ceramic Capacitor, 0.1 µF, 50 V, 0402 [1005 Metric], ± 10%, X5R, GRM Series"
			(at 140.97 116.84 0)
			(effects
				(font
					(size 1.27 1.27)
				)
				(hide yes)
			)
		)
		(property "MPN" "GRM155R61H104KE14D"
			(at 158.75 96.52 0)
			(effects
				(font
					(size 1.27 1.27)
					(thickness 0.15)
				)
				(justify left bottom)
				(hide yes)
			)
		)
		(property "Manufacturer" "Murata"
			(at 161.29 96.52 0)
			(effects
				(font
					(size 1.27 1.27)
					(thickness 0.15)
				)
				(justify left bottom)
				(hide yes)
			)
		)
		(property "License" "Apache-2.0"
			(at 163.83 96.52 0)
			(effects
				(font
					(size 1.27 1.27)
					(thickness 0.15)
				)
				(justify left bottom)
				(hide yes)
			)
		)
		(property "Author" "Antmicro"
			(at 166.37 96.52 0)
			(effects
				(font
					(size 1.27 1.27)
					(thickness 0.15)
				)
				(justify left bottom)
				(hide yes)
			)
		)
		(property "Val" "100n"
			(at 143.51 115.5636 90)
			(effects
				(font
					(size 1.27 1.27)
					(thickness 0.15)
				)
				(justify right)
			)
		)
		(property "Voltage" "50V"
			(at 168.91 96.52 0)
			(effects
				(font
					(size 1.27 1.27)
				)
				(justify left bottom)
				(hide yes)
			)
		)
		(property "Dielectric" "X5R"
			(at 171.45 96.52 0)
			(effects
				(font
					(size 1.27 1.27)
				)
				(justify left bottom)
				(hide yes)
			)
		)
		(pin "1"
		)
		(pin "2"
		)
		(instances
			(project "oculink-to-pcie-adapter"
				(path ""
					(reference "C41")
					(unit 1)
				)
			)
		)
	)
	(symbol
		(lib_id "antmicropower:GND")
		(at 152.4 203.2 0)
		(unit 1)
		(exclude_from_sim no)
		(in_bom yes)
		(on_board yes)
		(dnp no)
		(property "Reference" "#PWR072"
			(at 152.4 203.2 0)
			(effects
				(font
					(size 1.27 1.27)
				)
				(justify left)
				(hide yes)
			)
		)
		(property "Value" "GND"
			(at 152.4 207.01 0)
			(effects
				(font
					(size 1.27 1.27)
				)
			)
		)
		(property "Footprint" ""
			(at 152.4 203.2 0)
			(effects
				(font
					(size 1.27 1.27)
					(thickness 0.15)
				)
				(justify left bottom)
				(hide yes)
			)
		)
		(property "Datasheet" ""
			(at 152.4 203.2 0)
			(effects
				(font
					(size 1.27 1.27)
					(thickness 0.15)
				)
				(justify left bottom)
				(hide yes)
			)
		)
		(property "Description" ""
			(at 152.4 203.2 0)
			(effects
				(font
					(size 1.27 1.27)
				)
				(hide yes)
			)
		)
		(property "Author" "Antmicro"
			(at 161.29 210.82 0)
			(effects
				(font
					(size 1.27 1.27)
					(thickness 0.15)
				)
				(justify left bottom)
				(hide yes)
			)
		)
		(property "License" "Apache-2.0"
			(at 161.29 213.36 0)
			(effects
				(font
					(size 1.27 1.27)
					(thickness 0.15)
				)
				(justify left bottom)
				(hide yes)
			)
		)
		(pin "1"
		)
		(instances
			(project "oculink-to-pcie-adapter"
				(path ""
					(reference "#PWR072")
					(unit 1)
				)
			)
		)
	)
	(symbol
		(lib_id "antmicropower:GND")
		(at 134.62 203.2 0)
		(unit 1)
		(exclude_from_sim no)
		(in_bom yes)
		(on_board yes)
		(dnp no)
		(property "Reference" "#PWR071"
			(at 134.62 203.2 0)
			(effects
				(font
					(size 1.27 1.27)
				)
				(justify left)
				(hide yes)
			)
		)
		(property "Value" "GND"
			(at 134.62 207.01 0)
			(effects
				(font
					(size 1.27 1.27)
				)
			)
		)
		(property "Footprint" ""
			(at 134.62 203.2 0)
			(effects
				(font
					(size 1.27 1.27)
					(thickness 0.15)
				)
				(justify left bottom)
				(hide yes)
			)
		)
		(property "Datasheet" ""
			(at 134.62 203.2 0)
			(effects
				(font
					(size 1.27 1.27)
					(thickness 0.15)
				)
				(justify left bottom)
				(hide yes)
			)
		)
		(property "Description" ""
			(at 134.62 203.2 0)
			(effects
				(font
					(size 1.27 1.27)
				)
				(hide yes)
			)
		)
		(property "Author" "Antmicro"
			(at 143.51 210.82 0)
			(effects
				(font
					(size 1.27 1.27)
					(thickness 0.15)
				)
				(justify left bottom)
				(hide yes)
			)
		)
		(property "License" "Apache-2.0"
			(at 143.51 213.36 0)
			(effects
				(font
					(size 1.27 1.27)
					(thickness 0.15)
				)
				(justify left bottom)
				(hide yes)
			)
		)
		(pin "1"
		)
		(instances
			(project "oculink-to-pcie-adapter"
				(path ""
					(reference "#PWR071")
					(unit 1)
				)
			)
		)
	)
	(symbol
		(lib_id "antmicropower:GND")
		(at 295.91 237.49 0)
		(unit 1)
		(exclude_from_sim no)
		(in_bom yes)
		(on_board yes)
		(dnp no)
		(property "Reference" "#PWR065"
			(at 295.91 237.49 0)
			(effects
				(font
					(size 1.27 1.27)
				)
				(justify left)
				(hide yes)
			)
		)
		(property "Value" "GND"
			(at 295.91 241.3 0)
			(effects
				(font
					(size 1.27 1.27)
				)
			)
		)
		(property "Footprint" ""
			(at 295.91 237.49 0)
			(effects
				(font
					(size 1.27 1.27)
					(thickness 0.15)
				)
				(justify left bottom)
				(hide yes)
			)
		)
		(property "Datasheet" ""
			(at 295.91 237.49 0)
			(effects
				(font
					(size 1.27 1.27)
					(thickness 0.15)
				)
				(justify left bottom)
				(hide yes)
			)
		)
		(property "Description" ""
			(at 295.91 237.49 0)
			(effects
				(font
					(size 1.27 1.27)
				)
				(hide yes)
			)
		)
		(property "Author" "Antmicro"
			(at 304.8 245.11 0)
			(effects
				(font
					(size 1.27 1.27)
					(thickness 0.15)
				)
				(justify left bottom)
				(hide yes)
			)
		)
		(property "License" "Apache-2.0"
			(at 304.8 247.65 0)
			(effects
				(font
					(size 1.27 1.27)
					(thickness 0.15)
				)
				(justify left bottom)
				(hide yes)
			)
		)
		(pin "1"
		)
		(instances
			(project "oculink-to-pcie-adapter"
				(path ""
					(reference "#PWR065")
					(unit 1)
				)
			)
		)
	)
	(symbol
		(lib_id "antmicroTransistorsFETsMOSFETsSingle:SQS401EN-T1_BE3")
		(at 238.76 59.69 270)
		(mirror x)
		(unit 1)
		(exclude_from_sim no)
		(in_bom yes)
		(on_board yes)
		(dnp no)
		(fields_autoplaced yes)
		(property "Reference" "Q6"
			(at 241.3 46.99 90)
			(effects
				(font
					(size 1.27 1.27)
					(thickness 0.15)
				)
			)
		)
		(property "Value" "SQS401EN-T1_BE3"
			(at 228.6 44.45 0)
			(effects
				(font
					(size 1.27 1.27)
					(thickness 0.15)
				)
				(justify left bottom)
				(hide yes)
			)
		)
		(property "Footprint" "antmicro-footprints:Vishay_PowerPAK_1212-8_Single"
			(at 226.06 44.45 0)
			(effects
				(font
					(size 1.27 1.27)
					(thickness 0.15)
				)
				(justify left bottom)
				(hide yes)
			)
		)
		(property "Datasheet" "https://www.vishay.com/docs/65529/sqs401en.pdf"
			(at 223.52 44.45 0)
			(effects
				(font
					(size 1.27 1.27)
					(thickness 0.15)
				)
				(justify left bottom)
				(hide yes)
			)
		)
		(property "Description" "MOSFET, P Channel, 40 V, 16A, 0.047 ohm, PowerPAK 1212-8, Surface Mount"
			(at 238.76 59.69 0)
			(effects
				(font
					(size 1.27 1.27)
				)
				(hide yes)
			)
		)
		(property "MPN" "SQS401EN-T1_BE3"
			(at 241.3 49.53 90)
			(effects
				(font
					(size 1.27 1.27)
					(thickness 0.15)
				)
			)
		)
		(property "Manufacturer" "Vishay"
			(at 220.98 44.45 0)
			(effects
				(font
					(size 1.27 1.27)
					(thickness 0.15)
				)
				(justify left bottom)
				(hide yes)
			)
		)
		(property "Author" "Antmicro"
			(at 218.44 44.45 0)
			(effects
				(font
					(size 1.27 1.27)
					(thickness 0.15)
				)
				(justify left bottom)
				(hide yes)
			)
		)
		(property "License" "Apache-2.0"
			(at 215.9 44.45 0)
			(effects
				(font
					(size 1.27 1.27)
					(thickness 0.15)
				)
				(justify left bottom)
				(hide yes)
			)
		)
		(pin "4"
		)
		(pin "1"
		)
		(pin "3"
		)
		(pin "5"
		)
		(pin "2"
		)
		(instances
			(project "oculink-to-pcie-adapter"
				(path ""
					(reference "Q6")
					(unit 1)
				)
			)
		)
	)
	(symbol
		(lib_id "antmicroCapacitors0402:C_4u7_25V_0402")
		(at 102.87 87.63 90)
		(unit 1)
		(exclude_from_sim no)
		(in_bom yes)
		(on_board yes)
		(dnp no)
		(fields_autoplaced yes)
		(property "Reference" "C9"
			(at 105.41 83.8136 90)
			(effects
				(font
					(size 1.27 1.27)
					(thickness 0.15)
				)
				(justify right)
			)
		)
		(property "Value" "C_4u7_25V_0402"
			(at 113.03 67.31 0)
			(effects
				(font
					(size 1.27 1.27)
					(thickness 0.15)
				)
				(justify left bottom)
				(hide yes)
			)
		)
		(property "Footprint" "antmicro-footprints:C_0402_1005Metric"
			(at 115.57 67.31 0)
			(effects
				(font
					(size 1.27 1.27)
					(thickness 0.15)
				)
				(justify left bottom)
				(hide yes)
			)
		)
		(property "Datasheet" "https://www.murata.com/products/productdetail?partno=GRM155C61E475ME15%23"
			(at 118.11 67.31 0)
			(effects
				(font
					(size 1.27 1.27)
					(thickness 0.15)
				)
				(justify left bottom)
				(hide yes)
			)
		)
		(property "Description" "SMD Multilayer Ceramic Capacitor"
			(at 102.87 87.63 0)
			(effects
				(font
					(size 1.27 1.27)
				)
				(hide yes)
			)
		)
		(property "MPN" "GRM155C61E475ME15J"
			(at 120.65 67.31 0)
			(effects
				(font
					(size 1.27 1.27)
					(thickness 0.15)
				)
				(justify left bottom)
				(hide yes)
			)
		)
		(property "Manufacturer" "Murata"
			(at 123.19 67.31 0)
			(effects
				(font
					(size 1.27 1.27)
					(thickness 0.15)
				)
				(justify left bottom)
				(hide yes)
			)
		)
		(property "License" "Apache-2.0"
			(at 125.73 67.31 0)
			(effects
				(font
					(size 1.27 1.27)
					(thickness 0.15)
				)
				(justify left bottom)
				(hide yes)
			)
		)
		(property "Author" "Antmicro"
			(at 128.27 67.31 0)
			(effects
				(font
					(size 1.27 1.27)
					(thickness 0.15)
				)
				(justify left bottom)
				(hide yes)
			)
		)
		(property "Val" "4u7"
			(at 105.41 86.3536 90)
			(effects
				(font
					(size 1.27 1.27)
					(thickness 0.15)
				)
				(justify right)
			)
		)
		(property "Voltage" "25V"
			(at 130.81 67.31 0)
			(effects
				(font
					(size 1.27 1.27)
				)
				(justify left bottom)
				(hide yes)
			)
		)
		(property "Dielectric" "X5S"
			(at 133.35 67.31 0)
			(effects
				(font
					(size 1.27 1.27)
				)
				(justify left bottom)
				(hide yes)
			)
		)
		(pin "2"
		)
		(pin "1"
		)
		(instances
			(project "oculink-to-pcie-adapter"
				(path ""
					(reference "C9")
					(unit 1)
				)
			)
		)
	)
	(symbol
		(lib_id "antmicroTransistorsFETsMOSFETsSingle:BSS138-7-F")
		(at 251.46 124.46 0)
		(unit 1)
		(exclude_from_sim no)
		(in_bom yes)
		(on_board yes)
		(dnp no)
		(property "Reference" "Q8"
			(at 261.62 120.65 0)
			(effects
				(font
					(size 1.27 1.27)
					(thickness 0.15)
				)
				(justify left)
			)
		)
		(property "Value" "BSS138-7-F"
			(at 274.32 129.54 0)
			(effects
				(font
					(size 1.27 1.27)
					(thickness 0.15)
				)
				(justify left bottom)
				(hide yes)
			)
		)
		(property "Footprint" "antmicro-footprints:SOT-23-3"
			(at 274.32 132.08 0)
			(effects
				(font
					(size 1.27 1.27)
					(thickness 0.15)
				)
				(justify left bottom)
				(hide yes)
			)
		)
		(property "Datasheet" "https://www.diodes.com/assets/Datasheets/ds30144.pdf"
			(at 274.32 134.62 0)
			(effects
				(font
					(size 1.27 1.27)
					(thickness 0.15)
				)
				(justify left bottom)
				(hide yes)
			)
		)
		(property "Description" "Power MOSFET, N Channel, 50 V, 200 mA, 1.4 ohm, SOT-23, Surface Mount"
			(at 311.404 146.304 0)
			(effects
				(font
					(size 1.27 1.27)
				)
				(hide yes)
			)
		)
		(property "MPN" "BSS138-7-F"
			(at 261.62 123.19 0)
			(effects
				(font
					(size 1.27 1.27)
					(thickness 0.15)
				)
				(justify left)
			)
		)
		(property "Manufacturer" "Diodes Incorporated"
			(at 274.32 139.7 0)
			(effects
				(font
					(size 1.27 1.27)
					(thickness 0.15)
				)
				(justify left bottom)
				(hide yes)
			)
		)
		(property "Author" "Antmicro"
			(at 274.32 142.24 0)
			(effects
				(font
					(size 1.27 1.27)
					(thickness 0.15)
				)
				(justify left bottom)
				(hide yes)
			)
		)
		(property "License" "Apache-2.0"
			(at 274.32 144.78 0)
			(effects
				(font
					(size 1.27 1.27)
					(thickness 0.15)
				)
				(justify left bottom)
				(hide yes)
			)
		)
		(pin "2"
		)
		(pin "3"
		)
		(pin "1"
		)
		(instances
			(project "oculink-to-pcie-adapter"
				(path ""
					(reference "Q8")
					(unit 1)
				)
			)
		)
	)
	(symbol
		(lib_id "antmicroLEDIndicationDiscrete:LED_RGB_PLCC4_ASMB_MTB1_0A3A2")
		(at 299.72 72.39 90)
		(unit 1)
		(exclude_from_sim no)
		(in_bom yes)
		(on_board yes)
		(dnp no)
		(fields_autoplaced yes)
		(property "Reference" "D4"
			(at 312.42 61.5949 90)
			(effects
				(font
					(size 1.27 1.27)
				)
				(justify right)
			)
		)
		(property "Value" "LED_RGB_PLCC4_ASMB_MTB1_0A3A2"
			(at 307.34 44.45 0)
			(effects
				(font
					(size 1.27 1.27)
				)
				(justify left bottom)
				(hide yes)
			)
		)
		(property "Footprint" "antmicro-footprints:PLCC4_3.2x2.8mm"
			(at 309.88 44.45 0)
			(effects
				(font
					(size 1.27 1.27)
				)
				(justify left bottom)
				(hide yes)
			)
		)
		(property "Datasheet" "https://docs.broadcom.com/doc/AV02-4194EN"
			(at 312.42 44.45 0)
			(effects
				(font
					(size 1.27 1.27)
				)
				(justify left bottom)
				(hide yes)
			)
		)
		(property "Description" "LED, RGB, SMD, PLCC-4, R 20 mA, G 20 mA, B 20 mA, R 2.1 V, G 3.1 V, B 3.1 V, Common Anode"
			(at 299.72 72.39 0)
			(effects
				(font
					(size 1.27 1.27)
				)
				(hide yes)
			)
		)
		(property "MPN" "ASMB-MTB1-0A3A2"
			(at 314.96 44.45 0)
			(effects
				(font
					(size 1.27 1.27)
				)
				(justify left bottom)
				(hide yes)
			)
		)
		(property "Manufacturer" "Avago Technologies"
			(at 317.5 44.45 0)
			(effects
				(font
					(size 1.27 1.27)
				)
				(justify left bottom)
				(hide yes)
			)
		)
		(property "Color" "R, G, B"
			(at 312.42 64.1349 90)
			(effects
				(font
					(size 1.27 1.27)
				)
				(justify right)
			)
		)
		(property "Author" "Antmicro"
			(at 320.04 44.45 0)
			(effects
				(font
					(size 1.27 1.27)
				)
				(justify left bottom)
				(hide yes)
			)
		)
		(property "License" "Apache-2.0"
			(at 322.58 44.45 0)
			(effects
				(font
					(size 1.27 1.27)
				)
				(justify left bottom)
				(hide yes)
			)
		)
		(pin "3"
		)
		(pin "2"
		)
		(pin "4"
		)
		(pin "1"
		)
		(instances
			(project "oculink-to-pcie-adapter"
				(path ""
					(reference "D4")
					(unit 1)
				)
			)
		)
	)
	(symbol
		(lib_id "antmicroTransistorsFETsMOSFETsSingle:BSS138-7-F")
		(at 304.8 123.19 0)
		(unit 1)
		(exclude_from_sim no)
		(in_bom yes)
		(on_board yes)
		(dnp no)
		(property "Reference" "Q4"
			(at 314.96 119.38 0)
			(effects
				(font
					(size 1.27 1.27)
					(thickness 0.15)
				)
				(justify left)
			)
		)
		(property "Value" "BSS138-7-F"
			(at 327.66 128.27 0)
			(effects
				(font
					(size 1.27 1.27)
					(thickness 0.15)
				)
				(justify left bottom)
				(hide yes)
			)
		)
		(property "Footprint" "antmicro-footprints:SOT-23-3"
			(at 327.66 130.81 0)
			(effects
				(font
					(size 1.27 1.27)
					(thickness 0.15)
				)
				(justify left bottom)
				(hide yes)
			)
		)
		(property "Datasheet" "https://www.diodes.com/assets/Datasheets/ds30144.pdf"
			(at 327.66 133.35 0)
			(effects
				(font
					(size 1.27 1.27)
					(thickness 0.15)
				)
				(justify left bottom)
				(hide yes)
			)
		)
		(property "Description" "Power MOSFET, N Channel, 50 V, 200 mA, 1.4 ohm, SOT-23, Surface Mount"
			(at 364.744 145.034 0)
			(effects
				(font
					(size 1.27 1.27)
				)
				(hide yes)
			)
		)
		(property "MPN" "BSS138-7-F"
			(at 314.96 121.92 0)
			(effects
				(font
					(size 1.27 1.27)
					(thickness 0.15)
				)
				(justify left)
			)
		)
		(property "Manufacturer" "Diodes Incorporated"
			(at 327.66 138.43 0)
			(effects
				(font
					(size 1.27 1.27)
					(thickness 0.15)
				)
				(justify left bottom)
				(hide yes)
			)
		)
		(property "Author" "Antmicro"
			(at 327.66 140.97 0)
			(effects
				(font
					(size 1.27 1.27)
					(thickness 0.15)
				)
				(justify left bottom)
				(hide yes)
			)
		)
		(property "License" "Apache-2.0"
			(at 327.66 143.51 0)
			(effects
				(font
					(size 1.27 1.27)
					(thickness 0.15)
				)
				(justify left bottom)
				(hide yes)
			)
		)
		(pin "2"
		)
		(pin "3"
		)
		(pin "1"
		)
		(instances
			(project "oculink-to-pcie-adapter"
				(path ""
					(reference "Q4")
					(unit 1)
				)
			)
		)
	)
	(symbol
		(lib_id "antmicropower:GND")
		(at 381 109.22 0)
		(unit 1)
		(exclude_from_sim no)
		(in_bom yes)
		(on_board yes)
		(dnp no)
		(property "Reference" "#PWR052"
			(at 389.89 111.76 0)
			(effects
				(font
					(size 1.27 1.27)
					(thickness 0.15)
				)
				(justify left bottom)
				(hide yes)
			)
		)
		(property "Value" "GND"
			(at 381 113.03 0)
			(effects
				(font
					(size 1.27 1.27)
					(thickness 0.15)
				)
			)
		)
		(property "Footprint" ""
			(at 389.89 116.84 0)
			(effects
				(font
					(size 1.27 1.27)
					(thickness 0.15)
				)
				(justify left bottom)
				(hide yes)
			)
		)
		(property "Datasheet" ""
			(at 389.89 121.92 0)
			(effects
				(font
					(size 1.27 1.27)
					(thickness 0.15)
				)
				(justify left bottom)
				(hide yes)
			)
		)
		(property "Description" ""
			(at 381 109.22 0)
			(effects
				(font
					(size 1.27 1.27)
				)
				(hide yes)
			)
		)
		(property "Author" "Antmicro"
			(at 389.89 116.84 0)
			(effects
				(font
					(size 1.27 1.27)
					(thickness 0.15)
				)
				(justify left bottom)
				(hide yes)
			)
		)
		(property "License" "Apache-2.0"
			(at 389.89 119.38 0)
			(effects
				(font
					(size 1.27 1.27)
					(thickness 0.15)
				)
				(justify left bottom)
				(hide yes)
			)
		)
		(pin "1"
		)
		(instances
			(project "oculink-to-pcie-adapter"
				(path ""
					(reference "#PWR052")
					(unit 1)
				)
			)
		)
	)
	(symbol
		(lib_id "antmicroResistors0402:R_1k_0402")
		(at 381 106.68 90)
		(unit 1)
		(exclude_from_sim no)
		(in_bom no)
		(on_board yes)
		(dnp yes)
		(property "Reference" "R28"
			(at 382.27 102.87 90)
			(effects
				(font
					(size 1.27 1.27)
					(thickness 0.15)
				)
				(justify right)
			)
		)
		(property "Value" "R_1k_0402"
			(at 393.7 86.36 0)
			(effects
				(font
					(size 1.27 1.27)
					(thickness 0.15)
				)
				(justify left bottom)
				(hide yes)
			)
		)
		(property "Footprint" "antmicro-footprints:R_0402_1005Metric"
			(at 396.24 86.36 0)
			(effects
				(font
					(size 1.27 1.27)
					(thickness 0.15)
				)
				(justify left bottom)
				(hide yes)
			)
		)
		(property "Datasheet" "https://www.bourns.com/docs/product-datasheets/cr.pdf"
			(at 398.78 86.36 0)
			(effects
				(font
					(size 1.27 1.27)
					(thickness 0.15)
				)
				(justify left bottom)
				(hide yes)
			)
		)
		(property "Description" "SMD Chip Resistor, 1 kohm, ± 1%, 63 mW, 0402 [1005 Metric], Thick Film, General Purpose"
			(at 381 106.68 0)
			(effects
				(font
					(size 1.27 1.27)
				)
				(hide yes)
			)
		)
		(property "MPN" "CR0402-FX-1001GLF"
			(at 401.32 86.36 0)
			(effects
				(font
					(size 1.27 1.27)
					(thickness 0.15)
				)
				(justify left bottom)
				(hide yes)
			)
		)
		(property "Manufacturer" "Bourns"
			(at 403.86 86.36 0)
			(effects
				(font
					(size 1.27 1.27)
					(thickness 0.15)
				)
				(justify left bottom)
				(hide yes)
			)
		)
		(property "License" "Apache-2.0"
			(at 406.4 86.36 0)
			(effects
				(font
					(size 1.27 1.27)
					(thickness 0.15)
				)
				(justify left bottom)
				(hide yes)
			)
		)
		(property "Author" "Antmicro"
			(at 408.94 86.36 0)
			(effects
				(font
					(size 1.27 1.27)
					(thickness 0.15)
				)
				(justify left bottom)
				(hide yes)
			)
		)
		(property "Val" "1k"
			(at 382.27 105.41 90)
			(effects
				(font
					(size 1.27 1.27)
					(thickness 0.15)
				)
				(justify right)
			)
		)
		(property "Tolerance" "1%"
			(at 391.16 86.36 0)
			(effects
				(font
					(size 1.27 1.27)
				)
				(justify left bottom)
				(hide yes)
			)
		)
		(pin "2"
		)
		(pin "1"
		)
		(instances
			(project "oculink-to-pcie-adapter"
				(path ""
					(reference "R28")
					(unit 1)
				)
			)
		)
	)
	(symbol
		(lib_id "antmicroDCDCConverters:SIC477ED-T1-GE3")
		(at 176.53 200.66 0)
		(unit 1)
		(exclude_from_sim no)
		(in_bom yes)
		(on_board yes)
		(dnp no)
		(fields_autoplaced yes)
		(property "Reference" "U9"
			(at 190.5 193.04 0)
			(effects
				(font
					(size 1.27 1.27)
					(thickness 0.15)
				)
			)
		)
		(property "Value" "SIC477ED-T1-GE3"
			(at 190.5 234.315 0)
			(effects
				(font
					(size 1.27 1.27)
					(thickness 0.15)
				)
				(hide yes)
			)
		)
		(property "Footprint" "antmicro-footprints:SIC47XED-T1-GE3"
			(at 227.33 210.82 0)
			(effects
				(font
					(size 1.27 1.27)
					(thickness 0.15)
				)
				(justify left bottom)
				(hide yes)
			)
		)
		(property "Datasheet" "https://www.vishay.com/docs/77113/sic47x.pdf"
			(at 227.33 213.36 0)
			(effects
				(font
					(size 1.27 1.27)
					(thickness 0.15)
				)
				(justify left bottom)
				(hide yes)
			)
		)
		(property "Description" "DC/DC Synchronous Regulator, Adjustable, 4.5V to 55VIn, 0.8V to 50.6V/6AOut, 2MHz, PowerPAK MLP55-27"
			(at 176.53 200.66 0)
			(effects
				(font
					(size 1.27 1.27)
				)
				(hide yes)
			)
		)
		(property "Manufacturer" "Vishay"
			(at 227.33 215.9 0)
			(effects
				(font
					(size 1.27 1.27)
					(thickness 0.15)
				)
				(justify left bottom)
				(hide yes)
			)
		)
		(property "MPN" "SIC477ED-T1-GE3"
			(at 190.5 195.58 0)
			(effects
				(font
					(size 1.27 1.27)
					(thickness 0.15)
				)
			)
		)
		(property "Author" "Antmicro"
			(at 227.33 220.98 0)
			(effects
				(font
					(size 1.27 1.27)
					(thickness 0.15)
				)
				(justify left bottom)
				(hide yes)
			)
		)
		(property "License" "Apache-2.0"
			(at 227.33 223.52 0)
			(effects
				(font
					(size 1.27 1.27)
					(thickness 0.15)
				)
				(justify left bottom)
				(hide yes)
			)
		)
		(pin "1"
		)
		(pin "10"
		)
		(pin "11"
		)
		(pin "12"
		)
		(pin "13"
		)
		(pin "14"
		)
		(pin "15"
		)
		(pin "16"
		)
		(pin "17"
		)
		(pin "18"
		)
		(pin "19"
		)
		(pin "2"
		)
		(pin "20"
		)
		(pin "21"
		)
		(pin "22"
		)
		(pin "23"
		)
		(pin "24"
		)
		(pin "25"
		)
		(pin "26"
		)
		(pin "27"
		)
		(pin "28"
		)
		(pin "3"
		)
		(pin "4"
		)
		(pin "5"
		)
		(pin "6"
		)
		(pin "7"
		)
		(pin "8"
		)
		(pin "9"
		)
		(instances
			(project "oculink-to-pcie-adapter"
				(path ""
					(reference "U9")
					(unit 1)
				)
			)
		)
	)
	(symbol
		(lib_id "antmicroResistors0402:R_68k_0402")
		(at 303.53 80.01 90)
		(unit 1)
		(exclude_from_sim no)
		(in_bom yes)
		(on_board yes)
		(dnp no)
		(property "Reference" "R35"
			(at 304.8 76.2 90)
			(effects
				(font
					(size 1.27 1.27)
					(thickness 0.15)
				)
				(justify right)
			)
		)
		(property "Value" "R_68k_0402"
			(at 316.23 59.69 0)
			(effects
				(font
					(size 1.27 1.27)
					(thickness 0.15)
				)
				(justify left bottom)
				(hide yes)
			)
		)
		(property "Footprint" "antmicro-footprints:R_0402_1005Metric"
			(at 318.77 59.69 0)
			(effects
				(font
					(size 1.27 1.27)
					(thickness 0.15)
				)
				(justify left bottom)
				(hide yes)
			)
		)
		(property "Datasheet" "https://www.bourns.com/docs/product-datasheets/cr.pdf"
			(at 321.31 59.69 0)
			(effects
				(font
					(size 1.27 1.27)
					(thickness 0.15)
				)
				(justify left bottom)
				(hide yes)
			)
		)
		(property "Description" "SMD Chip Resistor"
			(at 303.53 80.01 0)
			(effects
				(font
					(size 1.27 1.27)
				)
				(hide yes)
			)
		)
		(property "MPN" "CR0402-FX-6802GLF"
			(at 323.85 59.69 0)
			(effects
				(font
					(size 1.27 1.27)
					(thickness 0.15)
				)
				(justify left bottom)
				(hide yes)
			)
		)
		(property "Manufacturer" "Bourns"
			(at 326.39 59.69 0)
			(effects
				(font
					(size 1.27 1.27)
					(thickness 0.15)
				)
				(justify left bottom)
				(hide yes)
			)
		)
		(property "License" "Apache-2.0"
			(at 328.93 59.69 0)
			(effects
				(font
					(size 1.27 1.27)
					(thickness 0.15)
				)
				(justify left bottom)
				(hide yes)
			)
		)
		(property "Author" "Antmicro"
			(at 331.47 59.69 0)
			(effects
				(font
					(size 1.27 1.27)
					(thickness 0.15)
				)
				(justify left bottom)
				(hide yes)
			)
		)
		(property "Val" "68k"
			(at 304.8 78.74 90)
			(effects
				(font
					(size 1.27 1.27)
					(thickness 0.15)
				)
				(justify right)
			)
		)
		(property "Tolerance" "1%"
			(at 313.69 59.69 0)
			(effects
				(font
					(size 1.27 1.27)
				)
				(justify left bottom)
				(hide yes)
			)
		)
		(pin "1"
		)
		(pin "2"
		)
		(instances
			(project ""
				(path ""
					(reference "R35")
					(unit 1)
				)
			)
		)
	)
	(symbol
		(lib_id "antmicropower:GND")
		(at 48.26 101.6 0)
		(unit 1)
		(exclude_from_sim no)
		(in_bom yes)
		(on_board yes)
		(dnp no)
		(property "Reference" "#PWR033"
			(at 57.15 104.14 0)
			(effects
				(font
					(size 1.27 1.27)
					(thickness 0.15)
				)
				(justify left bottom)
				(hide yes)
			)
		)
		(property "Value" "GND"
			(at 48.26 105.41 0)
			(effects
				(font
					(size 1.27 1.27)
					(thickness 0.15)
				)
			)
		)
		(property "Footprint" ""
			(at 57.15 109.22 0)
			(effects
				(font
					(size 1.27 1.27)
					(thickness 0.15)
				)
				(justify left bottom)
				(hide yes)
			)
		)
		(property "Datasheet" ""
			(at 57.15 114.3 0)
			(effects
				(font
					(size 1.27 1.27)
					(thickness 0.15)
				)
				(justify left bottom)
				(hide yes)
			)
		)
		(property "Description" ""
			(at 48.26 101.6 0)
			(effects
				(font
					(size 1.27 1.27)
				)
				(hide yes)
			)
		)
		(property "Author" "Antmicro"
			(at 57.15 109.22 0)
			(effects
				(font
					(size 1.27 1.27)
					(thickness 0.15)
				)
				(justify left bottom)
				(hide yes)
			)
		)
		(property "License" "Apache-2.0"
			(at 57.15 111.76 0)
			(effects
				(font
					(size 1.27 1.27)
					(thickness 0.15)
				)
				(justify left bottom)
				(hide yes)
			)
		)
		(pin "1"
		)
		(instances
			(project "oculink-to-pcie-adapter"
				(path ""
					(reference "#PWR033")
					(unit 1)
				)
			)
		)
	)
	(symbol
		(lib_id "antmicroCapacitorsmisc:C_10u_0805_35V")
		(at 134.62 201.93 90)
		(unit 1)
		(exclude_from_sim no)
		(in_bom yes)
		(on_board yes)
		(dnp no)
		(fields_autoplaced yes)
		(property "Reference" "C24"
			(at 137.16 198.1136 90)
			(effects
				(font
					(size 1.27 1.27)
					(thickness 0.15)
				)
				(justify right)
			)
		)
		(property "Value" "C_10u_0805_35V"
			(at 144.78 181.61 0)
			(effects
				(font
					(size 1.27 1.27)
					(thickness 0.15)
				)
				(justify left bottom)
				(hide yes)
			)
		)
		(property "Footprint" "antmicro-footprints:C_0805_2012Metric"
			(at 147.32 181.61 0)
			(effects
				(font
					(size 1.27 1.27)
					(thickness 0.15)
				)
				(justify left bottom)
				(hide yes)
			)
		)
		(property "Datasheet" "https://www.murata.com/products/productdetail?partno=GRM21BR6YA106KE43%23"
			(at 149.86 181.61 0)
			(effects
				(font
					(size 1.27 1.27)
					(thickness 0.15)
				)
				(justify left bottom)
				(hide yes)
			)
		)
		(property "Description" "SMD Multilayer Ceramic Capacitor, 10 µF, 35 V, 0805 [2012 Metric], ± 10%, X5R, GRM Series"
			(at 134.62 201.93 0)
			(effects
				(font
					(size 1.27 1.27)
				)
				(hide yes)
			)
		)
		(property "MPN" "GRM21BR6YA106KE43L"
			(at 152.4 181.61 0)
			(effects
				(font
					(size 1.27 1.27)
					(thickness 0.15)
				)
				(justify left bottom)
				(hide yes)
			)
		)
		(property "Manufacturer" "Murata"
			(at 154.94 181.61 0)
			(effects
				(font
					(size 1.27 1.27)
					(thickness 0.15)
				)
				(justify left bottom)
				(hide yes)
			)
		)
		(property "License" "Apache-2.0"
			(at 157.48 181.61 0)
			(effects
				(font
					(size 1.27 1.27)
					(thickness 0.15)
				)
				(justify left bottom)
				(hide yes)
			)
		)
		(property "Author" "Antmicro"
			(at 160.02 181.61 0)
			(effects
				(font
					(size 1.27 1.27)
					(thickness 0.15)
				)
				(justify left bottom)
				(hide yes)
			)
		)
		(property "Val" "10u"
			(at 137.16 200.6536 90)
			(effects
				(font
					(size 1.27 1.27)
					(thickness 0.15)
				)
				(justify right)
			)
		)
		(property "Voltage" "35V"
			(at 162.56 181.61 0)
			(effects
				(font
					(size 1.27 1.27)
				)
				(justify left bottom)
				(hide yes)
			)
		)
		(property "Dielectric" ""
			(at 165.1 181.61 0)
			(effects
				(font
					(size 1.27 1.27)
				)
				(justify left bottom)
				(hide yes)
			)
		)
		(property "Public" "False"
			(at 167.64 181.61 0)
			(effects
				(font
					(size 1.27 1.27)
				)
				(justify left bottom)
				(hide yes)
			)
		)
		(pin "2"
		)
		(pin "1"
		)
		(instances
			(project "oculink-to-pcie-adapter"
				(path ""
					(reference "C24")
					(unit 1)
				)
			)
		)
	)
	(symbol
		(lib_id "antmicropower:GND")
		(at 41.91 101.6 0)
		(unit 1)
		(exclude_from_sim no)
		(in_bom yes)
		(on_board yes)
		(dnp no)
		(property "Reference" "#PWR036"
			(at 50.8 104.14 0)
			(effects
				(font
					(size 1.27 1.27)
					(thickness 0.15)
				)
				(justify left bottom)
				(hide yes)
			)
		)
		(property "Value" "GND"
			(at 41.91 105.41 0)
			(effects
				(font
					(size 1.27 1.27)
					(thickness 0.15)
				)
			)
		)
		(property "Footprint" ""
			(at 50.8 109.22 0)
			(effects
				(font
					(size 1.27 1.27)
					(thickness 0.15)
				)
				(justify left bottom)
				(hide yes)
			)
		)
		(property "Datasheet" ""
			(at 50.8 114.3 0)
			(effects
				(font
					(size 1.27 1.27)
					(thickness 0.15)
				)
				(justify left bottom)
				(hide yes)
			)
		)
		(property "Description" ""
			(at 41.91 101.6 0)
			(effects
				(font
					(size 1.27 1.27)
				)
				(hide yes)
			)
		)
		(property "Author" "Antmicro"
			(at 50.8 109.22 0)
			(effects
				(font
					(size 1.27 1.27)
					(thickness 0.15)
				)
				(justify left bottom)
				(hide yes)
			)
		)
		(property "License" "Apache-2.0"
			(at 50.8 111.76 0)
			(effects
				(font
					(size 1.27 1.27)
					(thickness 0.15)
				)
				(justify left bottom)
				(hide yes)
			)
		)
		(pin "1"
		)
		(instances
			(project "oculink-to-pcie-adapter"
				(path ""
					(reference "#PWR036")
					(unit 1)
				)
			)
		)
	)
	(symbol
		(lib_id "antmicroResistors0402:R_49k9_0402")
		(at 223.52 104.14 0)
		(unit 1)
		(exclude_from_sim no)
		(in_bom yes)
		(on_board yes)
		(dnp no)
		(property "Reference" "R20"
			(at 221.742 102.87 0)
			(effects
				(font
					(size 1.27 1.27)
					(thickness 0.15)
				)
			)
		)
		(property "Value" "R_49k9_0402"
			(at 243.84 116.84 0)
			(effects
				(font
					(size 1.27 1.27)
					(thickness 0.15)
				)
				(justify left bottom)
				(hide yes)
			)
		)
		(property "Footprint" "antmicro-footprints:R_0402_1005Metric"
			(at 243.84 119.38 0)
			(effects
				(font
					(size 1.27 1.27)
					(thickness 0.15)
				)
				(justify left bottom)
				(hide yes)
			)
		)
		(property "Datasheet" "https://www.bourns.com/docs/product-datasheets/cr.pdf"
			(at 243.84 121.92 0)
			(effects
				(font
					(size 1.27 1.27)
					(thickness 0.15)
				)
				(justify left bottom)
				(hide yes)
			)
		)
		(property "Description" "SMD Chip Resistor, 49.9 kohm, ± 1%, 63 mW, 0402 [1005 Metric], Thick Film, General Purpose"
			(at 223.52 104.14 0)
			(effects
				(font
					(size 1.27 1.27)
				)
				(hide yes)
			)
		)
		(property "MPN" "CR0402-FX-4992GLF"
			(at 243.84 124.46 0)
			(effects
				(font
					(size 1.27 1.27)
					(thickness 0.15)
				)
				(justify left bottom)
				(hide yes)
			)
		)
		(property "Manufacturer" "Bourns"
			(at 243.84 127 0)
			(effects
				(font
					(size 1.27 1.27)
					(thickness 0.15)
				)
				(justify left bottom)
				(hide yes)
			)
		)
		(property "License" "Apache-2.0"
			(at 243.84 129.54 0)
			(effects
				(font
					(size 1.27 1.27)
					(thickness 0.15)
				)
				(justify left bottom)
				(hide yes)
			)
		)
		(property "Author" "Antmicro"
			(at 243.84 132.08 0)
			(effects
				(font
					(size 1.27 1.27)
					(thickness 0.15)
				)
				(justify left bottom)
				(hide yes)
			)
		)
		(property "Val" "49k9"
			(at 230.886 103.124 0)
			(effects
				(font
					(size 1.27 1.27)
					(thickness 0.15)
				)
			)
		)
		(property "Tolerance" "1%"
			(at 243.84 114.3 0)
			(effects
				(font
					(size 1.27 1.27)
				)
				(justify left bottom)
				(hide yes)
			)
		)
		(pin "2"
		)
		(pin "1"
		)
		(instances
			(project ""
				(path ""
					(reference "R20")
					(unit 1)
				)
			)
		)
	)
	(symbol
		(lib_id "antmicroCapacitors0402:C_1u_25V_0402")
		(at 161.29 116.84 90)
		(unit 1)
		(exclude_from_sim no)
		(in_bom yes)
		(on_board yes)
		(dnp no)
		(property "Reference" "C11"
			(at 163.322 113.03 90)
			(effects
				(font
					(size 1.27 1.27)
					(thickness 0.15)
				)
				(justify right)
			)
		)
		(property "Value" "C_1u_25V_0402"
			(at 171.45 96.52 0)
			(effects
				(font
					(size 1.27 1.27)
					(thickness 0.15)
				)
				(justify left bottom)
				(hide yes)
			)
		)
		(property "Footprint" "antmicro-footprints:C_0402_1005Metric"
			(at 173.99 96.52 0)
			(effects
				(font
					(size 1.27 1.27)
					(thickness 0.15)
				)
				(justify left bottom)
				(hide yes)
			)
		)
		(property "Datasheet" "https://www.murata.com/products/productdetail?partno=GRM155R61E105KE11%23"
			(at 176.53 96.52 0)
			(effects
				(font
					(size 1.27 1.27)
					(thickness 0.15)
				)
				(justify left bottom)
				(hide yes)
			)
		)
		(property "Description" "SMD Multilayer Ceramic Capacitor, 1 µF, 25 V, 0402 [1005 Metric], ± 10%, X5R, GRM Series"
			(at 161.29 116.84 0)
			(effects
				(font
					(size 1.27 1.27)
				)
				(hide yes)
			)
		)
		(property "MPN" "GRM155R61E105KE11J"
			(at 179.07 96.52 0)
			(effects
				(font
					(size 1.27 1.27)
					(thickness 0.15)
				)
				(justify left bottom)
				(hide yes)
			)
		)
		(property "Manufacturer" "Murata"
			(at 181.61 96.52 0)
			(effects
				(font
					(size 1.27 1.27)
					(thickness 0.15)
				)
				(justify left bottom)
				(hide yes)
			)
		)
		(property "License" "Apache-2.0"
			(at 184.15 96.52 0)
			(effects
				(font
					(size 1.27 1.27)
					(thickness 0.15)
				)
				(justify left bottom)
				(hide yes)
			)
		)
		(property "Author" "Antmicro"
			(at 186.69 96.52 0)
			(effects
				(font
					(size 1.27 1.27)
					(thickness 0.15)
				)
				(justify left bottom)
				(hide yes)
			)
		)
		(property "Val" "1u"
			(at 163.322 115.57 90)
			(effects
				(font
					(size 1.27 1.27)
					(thickness 0.15)
				)
				(justify right)
			)
		)
		(property "Voltage" "25V"
			(at 189.23 96.52 0)
			(effects
				(font
					(size 1.27 1.27)
				)
				(justify left bottom)
				(hide yes)
			)
		)
		(property "Dielectric" "X5R"
			(at 191.77 96.52 0)
			(effects
				(font
					(size 1.27 1.27)
				)
				(justify left bottom)
				(hide yes)
			)
		)
		(pin "1"
		)
		(pin "2"
		)
		(instances
			(project ""
				(path ""
					(reference "C11")
					(unit 1)
				)
			)
		)
	)
	(symbol
		(lib_id "antmicroTestPoints:TP_Pad0.75mm_Drill0.2mm")
		(at 269.24 52.07 90)
		(unit 1)
		(exclude_from_sim no)
		(in_bom no)
		(on_board yes)
		(dnp no)
		(fields_autoplaced yes)
		(property "Reference" "TP14"
			(at 271.78 48.895 90)
			(effects
				(font
					(size 1.27 1.27)
					(thickness 0.15)
				)
				(justify right)
			)
		)
		(property "Value" "TP_Pad0.75mm_Drill0.2mm"
			(at 273.05 41.91 0)
			(effects
				(font
					(size 1.27 1.27)
					(thickness 0.15)
				)
				(justify left bottom)
				(hide yes)
			)
		)
		(property "Footprint" "antmicro-footprints:TP_Pad0.75mm_Drill0.2mm"
			(at 275.59 41.91 0)
			(effects
				(font
					(size 1.27 1.27)
					(thickness 0.15)
				)
				(justify left bottom)
				(hide yes)
			)
		)
		(property "Datasheet" ""
			(at 281.94 34.29 0)
			(effects
				(font
					(size 1.27 1.27)
					(thickness 0.15)
				)
				(justify left bottom)
				(hide yes)
			)
		)
		(property "Description" "SMT test point"
			(at 269.24 52.07 0)
			(effects
				(font
					(size 1.27 1.27)
				)
				(hide yes)
			)
		)
		(property "MPN" ""
			(at 280.67 41.275 0)
			(effects
				(font
					(size 1.27 1.27)
					(thickness 0.15)
				)
				(justify left bottom)
				(hide yes)
			)
		)
		(property "Manufacturer" ""
			(at 275.59 41.275 0)
			(effects
				(font
					(size 1.27 1.27)
					(thickness 0.15)
				)
				(justify left bottom)
				(hide yes)
			)
		)
		(property "Author" "Antmicro"
			(at 278.13 41.91 0)
			(effects
				(font
					(size 1.27 1.27)
					(thickness 0.15)
				)
				(justify left bottom)
				(hide yes)
			)
		)
		(property "License" "Apache-2.0"
			(at 280.67 41.91 0)
			(effects
				(font
					(size 1.27 1.27)
					(thickness 0.15)
				)
				(justify left bottom)
				(hide yes)
			)
		)
		(pin "1"
		)
		(instances
			(project "oculink-to-pcie-adapter"
				(path ""
					(reference "TP14")
					(unit 1)
				)
			)
		)
	)
	(symbol
		(lib_id "antmicropower:GND")
		(at 242.57 237.49 0)
		(unit 1)
		(exclude_from_sim no)
		(in_bom yes)
		(on_board yes)
		(dnp no)
		(property "Reference" "#PWR077"
			(at 242.57 237.49 0)
			(effects
				(font
					(size 1.27 1.27)
				)
				(justify left)
				(hide yes)
			)
		)
		(property "Value" "GND"
			(at 242.57 241.3 0)
			(effects
				(font
					(size 1.27 1.27)
				)
			)
		)
		(property "Footprint" ""
			(at 242.57 237.49 0)
			(effects
				(font
					(size 1.27 1.27)
					(thickness 0.15)
				)
				(justify left bottom)
				(hide yes)
			)
		)
		(property "Datasheet" ""
			(at 242.57 237.49 0)
			(effects
				(font
					(size 1.27 1.27)
					(thickness 0.15)
				)
				(justify left bottom)
				(hide yes)
			)
		)
		(property "Description" ""
			(at 242.57 237.49 0)
			(effects
				(font
					(size 1.27 1.27)
				)
				(hide yes)
			)
		)
		(property "Author" "Antmicro"
			(at 251.46 245.11 0)
			(effects
				(font
					(size 1.27 1.27)
					(thickness 0.15)
				)
				(justify left bottom)
				(hide yes)
			)
		)
		(property "License" "Apache-2.0"
			(at 251.46 247.65 0)
			(effects
				(font
					(size 1.27 1.27)
					(thickness 0.15)
				)
				(justify left bottom)
				(hide yes)
			)
		)
		(pin "1"
		)
		(instances
			(project "oculink-to-pcie-adapter"
				(path ""
					(reference "#PWR077")
					(unit 1)
				)
			)
		)
	)
	(symbol
		(lib_id "antmicroResistors0402:R_1k_0402")
		(at 381 58.42 90)
		(unit 1)
		(exclude_from_sim no)
		(in_bom yes)
		(on_board yes)
		(dnp no)
		(property "Reference" "R4"
			(at 382.27 54.61 90)
			(effects
				(font
					(size 1.27 1.27)
					(thickness 0.15)
				)
				(justify right)
			)
		)
		(property "Value" "R_1k_0402"
			(at 393.7 38.1 0)
			(effects
				(font
					(size 1.27 1.27)
					(thickness 0.15)
				)
				(justify left bottom)
				(hide yes)
			)
		)
		(property "Footprint" "antmicro-footprints:R_0402_1005Metric"
			(at 396.24 38.1 0)
			(effects
				(font
					(size 1.27 1.27)
					(thickness 0.15)
				)
				(justify left bottom)
				(hide yes)
			)
		)
		(property "Datasheet" "https://www.bourns.com/docs/product-datasheets/cr.pdf"
			(at 398.78 38.1 0)
			(effects
				(font
					(size 1.27 1.27)
					(thickness 0.15)
				)
				(justify left bottom)
				(hide yes)
			)
		)
		(property "Description" "SMD Chip Resistor, 1 kohm, ± 1%, 63 mW, 0402 [1005 Metric], Thick Film, General Purpose"
			(at 381 58.42 0)
			(effects
				(font
					(size 1.27 1.27)
				)
				(hide yes)
			)
		)
		(property "MPN" "CR0402-FX-1001GLF"
			(at 401.32 38.1 0)
			(effects
				(font
					(size 1.27 1.27)
					(thickness 0.15)
				)
				(justify left bottom)
				(hide yes)
			)
		)
		(property "Manufacturer" "Bourns"
			(at 403.86 38.1 0)
			(effects
				(font
					(size 1.27 1.27)
					(thickness 0.15)
				)
				(justify left bottom)
				(hide yes)
			)
		)
		(property "License" "Apache-2.0"
			(at 406.4 38.1 0)
			(effects
				(font
					(size 1.27 1.27)
					(thickness 0.15)
				)
				(justify left bottom)
				(hide yes)
			)
		)
		(property "Author" "Antmicro"
			(at 408.94 38.1 0)
			(effects
				(font
					(size 1.27 1.27)
					(thickness 0.15)
				)
				(justify left bottom)
				(hide yes)
			)
		)
		(property "Val" "1k"
			(at 382.27 57.15 90)
			(effects
				(font
					(size 1.27 1.27)
					(thickness 0.15)
				)
				(justify right)
			)
		)
		(property "Tolerance" "1%"
			(at 391.16 38.1 0)
			(effects
				(font
					(size 1.27 1.27)
				)
				(justify left bottom)
				(hide yes)
			)
		)
		(pin "2"
		)
		(pin "1"
		)
		(instances
			(project "oculink-to-pcie-adapter"
				(path ""
					(reference "R4")
					(unit 1)
				)
			)
		)
	)
	(symbol
		(lib_id "antmicroResistors0402:R_10k_0402")
		(at 302.26 130.81 90)
		(unit 1)
		(exclude_from_sim no)
		(in_bom yes)
		(on_board yes)
		(dnp no)
		(property "Reference" "R49"
			(at 303.53 127.254 90)
			(effects
				(font
					(size 1.27 1.27)
					(thickness 0.15)
				)
				(justify right)
			)
		)
		(property "Value" "R_10k_0402"
			(at 314.96 110.49 0)
			(effects
				(font
					(size 1.27 1.27)
					(thickness 0.15)
				)
				(justify left bottom)
				(hide yes)
			)
		)
		(property "Footprint" "antmicro-footprints:R_0402_1005Metric"
			(at 317.5 110.49 0)
			(effects
				(font
					(size 1.27 1.27)
					(thickness 0.15)
				)
				(justify left bottom)
				(hide yes)
			)
		)
		(property "Datasheet" "https://www.bourns.com/docs/product-datasheets/cr.pdf"
			(at 320.04 110.49 0)
			(effects
				(font
					(size 1.27 1.27)
					(thickness 0.15)
				)
				(justify left bottom)
				(hide yes)
			)
		)
		(property "Description" "SMD Chip Resistor, 10 kohm, ± 1%, 62.5 mW, 0402 [1005 Metric], Thick Film, General Purpose"
			(at 302.26 130.81 0)
			(effects
				(font
					(size 1.27 1.27)
				)
				(hide yes)
			)
		)
		(property "MPN" "CR0402-FX-1002GLF"
			(at 322.58 110.49 0)
			(effects
				(font
					(size 1.27 1.27)
					(thickness 0.15)
				)
				(justify left bottom)
				(hide yes)
			)
		)
		(property "Manufacturer" "Bourns"
			(at 325.12 110.49 0)
			(effects
				(font
					(size 1.27 1.27)
					(thickness 0.15)
				)
				(justify left bottom)
				(hide yes)
			)
		)
		(property "License" "Apache-2.0"
			(at 327.66 110.49 0)
			(effects
				(font
					(size 1.27 1.27)
					(thickness 0.15)
				)
				(justify left bottom)
				(hide yes)
			)
		)
		(property "Author" "Antmicro"
			(at 330.2 110.49 0)
			(effects
				(font
					(size 1.27 1.27)
					(thickness 0.15)
				)
				(justify left bottom)
				(hide yes)
			)
		)
		(property "Val" "10k"
			(at 303.53 129.794 90)
			(effects
				(font
					(size 1.27 1.27)
					(thickness 0.15)
				)
				(justify right)
			)
		)
		(property "Tolerance" "1%"
			(at 312.42 110.49 0)
			(effects
				(font
					(size 1.27 1.27)
				)
				(justify left bottom)
				(hide yes)
			)
		)
		(pin "2"
		)
		(pin "1"
		)
		(instances
			(project "oculink-to-pcie-adapter"
				(path ""
					(reference "R49")
					(unit 1)
				)
			)
		)
	)
	(symbol
		(lib_id "antmicropower:GND")
		(at 302.26 133.35 0)
		(mirror y)
		(unit 1)
		(exclude_from_sim no)
		(in_bom yes)
		(on_board yes)
		(dnp no)
		(property "Reference" "#PWR064"
			(at 293.37 135.89 0)
			(effects
				(font
					(size 1.27 1.27)
					(thickness 0.15)
				)
				(justify left bottom)
				(hide yes)
			)
		)
		(property "Value" "GND"
			(at 302.26 137.16 0)
			(effects
				(font
					(size 1.27 1.27)
					(thickness 0.15)
				)
			)
		)
		(property "Footprint" ""
			(at 293.37 140.97 0)
			(effects
				(font
					(size 1.27 1.27)
					(thickness 0.15)
				)
				(justify left bottom)
				(hide yes)
			)
		)
		(property "Datasheet" ""
			(at 293.37 146.05 0)
			(effects
				(font
					(size 1.27 1.27)
					(thickness 0.15)
				)
				(justify left bottom)
				(hide yes)
			)
		)
		(property "Description" ""
			(at 302.26 133.35 0)
			(effects
				(font
					(size 1.27 1.27)
				)
				(hide yes)
			)
		)
		(property "Author" "Antmicro"
			(at 293.37 140.97 0)
			(effects
				(font
					(size 1.27 1.27)
					(thickness 0.15)
				)
				(justify left bottom)
				(hide yes)
			)
		)
		(property "License" "Apache-2.0"
			(at 293.37 143.51 0)
			(effects
				(font
					(size 1.27 1.27)
					(thickness 0.15)
				)
				(justify left bottom)
				(hide yes)
			)
		)
		(pin "1"
		)
		(instances
			(project "oculink-to-pcie-adapter"
				(path ""
					(reference "#PWR064")
					(unit 1)
				)
			)
		)
	)
	(symbol
		(lib_id "antmicroCapacitorsmisc:C_22u_25V_0805")
		(at 287.02 219.71 90)
		(unit 1)
		(exclude_from_sim no)
		(in_bom yes)
		(on_board yes)
		(dnp no)
		(property "Reference" "C18"
			(at 289.052 214.63 90)
			(effects
				(font
					(size 1.27 1.27)
					(thickness 0.15)
				)
				(justify right)
			)
		)
		(property "Value" "C_22u_25V_0805"
			(at 297.18 199.39 0)
			(effects
				(font
					(size 1.27 1.27)
					(thickness 0.15)
				)
				(justify left bottom)
				(hide yes)
			)
		)
		(property "Footprint" "antmicro-footprints:C_0805_2012Metric"
			(at 299.72 199.39 0)
			(effects
				(font
					(size 1.27 1.27)
					(thickness 0.15)
				)
				(justify left bottom)
				(hide yes)
			)
		)
		(property "Datasheet" "https://product.samsungsem.com/mlcc/CL21A226MAYNNN.do"
			(at 302.26 199.39 0)
			(effects
				(font
					(size 1.27 1.27)
					(thickness 0.15)
				)
				(justify left bottom)
				(hide yes)
			)
		)
		(property "Description" "SMT Multilayer Ceramic Capacitor, 22uF, +/-20%, 25V, X5R, 0805 [2012 Metric]"
			(at 287.02 219.71 0)
			(effects
				(font
					(size 1.27 1.27)
				)
				(hide yes)
			)
		)
		(property "MPN" "CL21A226MAYNNNE"
			(at 304.8 199.39 0)
			(effects
				(font
					(size 1.27 1.27)
					(thickness 0.15)
				)
				(justify left bottom)
				(hide yes)
			)
		)
		(property "Manufacturer" "Samsung Electro-Mechanics"
			(at 307.34 199.39 0)
			(effects
				(font
					(size 1.27 1.27)
					(thickness 0.15)
				)
				(justify left bottom)
				(hide yes)
			)
		)
		(property "License" "Apache-2.0"
			(at 309.88 199.39 0)
			(effects
				(font
					(size 1.27 1.27)
					(thickness 0.15)
				)
				(justify left bottom)
				(hide yes)
			)
		)
		(property "Author" "Antmicro"
			(at 312.42 199.39 0)
			(effects
				(font
					(size 1.27 1.27)
					(thickness 0.15)
				)
				(justify left bottom)
				(hide yes)
			)
		)
		(property "Val" "22u"
			(at 289.052 217.17 90)
			(effects
				(font
					(size 1.27 1.27)
					(thickness 0.15)
				)
				(justify right)
			)
		)
		(property "Voltage" "25V"
			(at 289.052 219.7099 90)
			(effects
				(font
					(size 1.27 1.27)
				)
				(justify right)
			)
		)
		(property "Dielectric" "X5R"
			(at 317.5 199.39 0)
			(effects
				(font
					(size 1.27 1.27)
				)
				(justify left bottom)
				(hide yes)
			)
		)
		(property "Public" "False"
			(at 320.04 199.39 0)
			(effects
				(font
					(size 1.27 1.27)
				)
				(justify left bottom)
				(hide yes)
			)
		)
		(pin "1"
		)
		(pin "2"
		)
		(instances
			(project "oculink-to-pcie-adapter"
				(path ""
					(reference "C18")
					(unit 1)
				)
			)
		)
	)
	(symbol
		(lib_id "antmicroTestPoints:TP_Pad0.75mm_Drill0.2mm")
		(at 218.44 91.44 0)
		(unit 1)
		(exclude_from_sim no)
		(in_bom no)
		(on_board yes)
		(dnp no)
		(fields_autoplaced yes)
		(property "Reference" "TP5"
			(at 223.52 91.44 0)
			(effects
				(font
					(size 1.27 1.27)
					(thickness 0.15)
				)
				(justify left)
			)
		)
		(property "Value" "TP_Pad0.75mm_Drill0.2mm"
			(at 228.6 95.25 0)
			(effects
				(font
					(size 1.27 1.27)
					(thickness 0.15)
				)
				(justify left bottom)
				(hide yes)
			)
		)
		(property "Footprint" "antmicro-footprints:TP_Pad0.75mm_Drill0.2mm"
			(at 228.6 97.79 0)
			(effects
				(font
					(size 1.27 1.27)
					(thickness 0.15)
				)
				(justify left bottom)
				(hide yes)
			)
		)
		(property "Datasheet" ""
			(at 236.22 104.14 0)
			(effects
				(font
					(size 1.27 1.27)
					(thickness 0.15)
				)
				(justify left bottom)
				(hide yes)
			)
		)
		(property "Description" "SMT test point"
			(at 218.44 91.44 0)
			(effects
				(font
					(size 1.27 1.27)
				)
				(hide yes)
			)
		)
		(property "MPN" ""
			(at 229.235 102.87 0)
			(effects
				(font
					(size 1.27 1.27)
					(thickness 0.15)
				)
				(justify left bottom)
				(hide yes)
			)
		)
		(property "Manufacturer" ""
			(at 229.235 97.79 0)
			(effects
				(font
					(size 1.27 1.27)
					(thickness 0.15)
				)
				(justify left bottom)
				(hide yes)
			)
		)
		(property "Author" "Antmicro"
			(at 228.6 100.33 0)
			(effects
				(font
					(size 1.27 1.27)
					(thickness 0.15)
				)
				(justify left bottom)
				(hide yes)
			)
		)
		(property "License" "Apache-2.0"
			(at 228.6 102.87 0)
			(effects
				(font
					(size 1.27 1.27)
					(thickness 0.15)
				)
				(justify left bottom)
				(hide yes)
			)
		)
		(pin "1"
		)
		(instances
			(project "oculink-to-pcie-adapter"
				(path ""
					(reference "TP5")
					(unit 1)
				)
			)
		)
	)
	(symbol
		(lib_id "antmicroUSBConnectors:USB-C_GCT_USB4105-GF-A")
		(at 39.37 63.5 0)
		(unit 1)
		(exclude_from_sim no)
		(in_bom yes)
		(on_board yes)
		(dnp no)
		(fields_autoplaced yes)
		(property "Reference" "J3"
			(at 26.035 55.88 0)
			(effects
				(font
					(size 1.27 1.27)
					(thickness 0.15)
				)
			)
		)
		(property "Value" "USB-C_GCT_USB4105-GF-A"
			(at 26.035 58.42 0)
			(effects
				(font
					(size 1.27 1.27)
					(thickness 0.15)
				)
				(hide yes)
			)
		)
		(property "Footprint" "antmicro-footprints:USB-C_Receptacle_GCT_USB4105-GF-A"
			(at 77.47 71.12 0)
			(effects
				(font
					(size 1.27 1.27)
					(thickness 0.15)
				)
				(justify left bottom)
				(hide yes)
			)
		)
		(property "Datasheet" "https://gct.co/files/drawings/usb4105.pdf"
			(at 77.47 73.66 0)
			(effects
				(font
					(size 1.27 1.27)
					(thickness 0.15)
				)
				(justify left bottom)
				(hide yes)
			)
		)
		(property "Description" "USB-C (USB TYPE-C) USB 2.0 Receptacle Connector 24 (16+8 Dummy) Position Surface Mount, Right Angle"
			(at 39.37 63.5 0)
			(effects
				(font
					(size 1.27 1.27)
				)
				(hide yes)
			)
		)
		(property "Manufacturer" "GCT"
			(at 77.47 76.2 0)
			(effects
				(font
					(size 1.27 1.27)
					(thickness 0.15)
				)
				(justify left bottom)
				(hide yes)
			)
		)
		(property "MPN" "USB4105-GF-A"
			(at 26.035 58.42 0)
			(effects
				(font
					(size 1.27 1.27)
					(thickness 0.15)
				)
			)
		)
		(property "Author" "Antmicro"
			(at 77.47 81.28 0)
			(effects
				(font
					(size 1.27 1.27)
					(thickness 0.15)
				)
				(justify left bottom)
				(hide yes)
			)
		)
		(property "License" "Apache-2.0"
			(at 77.47 83.82 0)
			(effects
				(font
					(size 1.27 1.27)
					(thickness 0.15)
				)
				(justify left bottom)
				(hide yes)
			)
		)
		(pin "B6"
		)
		(pin "A8"
		)
		(pin "A9"
		)
		(pin "B1"
		)
		(pin "B12"
		)
		(pin "B7"
		)
		(pin "B9"
		)
		(pin "A7"
		)
		(pin "A5"
		)
		(pin "B4"
		)
		(pin "A6"
		)
		(pin "B5"
		)
		(pin "A4"
		)
		(pin "A12"
		)
		(pin "A1"
		)
		(pin "B8"
		)
		(pin "SH"
		)
		(instances
			(project "oculink-to-pcie-adapter"
				(path ""
					(reference "J3")
					(unit 1)
				)
			)
		)
	)
	(symbol
		(lib_id "antmicroCapacitorsmisc:C_22u_25V_0805")
		(at 269.24 219.71 90)
		(unit 1)
		(exclude_from_sim no)
		(in_bom yes)
		(on_board yes)
		(dnp no)
		(property "Reference" "C16"
			(at 271.272 214.63 90)
			(effects
				(font
					(size 1.27 1.27)
					(thickness 0.15)
				)
				(justify right)
			)
		)
		(property "Value" "C_22u_25V_0805"
			(at 279.4 199.39 0)
			(effects
				(font
					(size 1.27 1.27)
					(thickness 0.15)
				)
				(justify left bottom)
				(hide yes)
			)
		)
		(property "Footprint" "antmicro-footprints:C_0805_2012Metric"
			(at 281.94 199.39 0)
			(effects
				(font
					(size 1.27 1.27)
					(thickness 0.15)
				)
				(justify left bottom)
				(hide yes)
			)
		)
		(property "Datasheet" "https://product.samsungsem.com/mlcc/CL21A226MAYNNN.do"
			(at 284.48 199.39 0)
			(effects
				(font
					(size 1.27 1.27)
					(thickness 0.15)
				)
				(justify left bottom)
				(hide yes)
			)
		)
		(property "Description" "SMT Multilayer Ceramic Capacitor, 22uF, +/-20%, 25V, X5R, 0805 [2012 Metric]"
			(at 269.24 219.71 0)
			(effects
				(font
					(size 1.27 1.27)
				)
				(hide yes)
			)
		)
		(property "MPN" "CL21A226MAYNNNE"
			(at 287.02 199.39 0)
			(effects
				(font
					(size 1.27 1.27)
					(thickness 0.15)
				)
				(justify left bottom)
				(hide yes)
			)
		)
		(property "Manufacturer" "Samsung Electro-Mechanics"
			(at 289.56 199.39 0)
			(effects
				(font
					(size 1.27 1.27)
					(thickness 0.15)
				)
				(justify left bottom)
				(hide yes)
			)
		)
		(property "License" "Apache-2.0"
			(at 292.1 199.39 0)
			(effects
				(font
					(size 1.27 1.27)
					(thickness 0.15)
				)
				(justify left bottom)
				(hide yes)
			)
		)
		(property "Author" "Antmicro"
			(at 294.64 199.39 0)
			(effects
				(font
					(size 1.27 1.27)
					(thickness 0.15)
				)
				(justify left bottom)
				(hide yes)
			)
		)
		(property "Val" "22u"
			(at 271.272 217.17 90)
			(effects
				(font
					(size 1.27 1.27)
					(thickness 0.15)
				)
				(justify right)
			)
		)
		(property "Voltage" "25V"
			(at 271.272 219.7099 90)
			(effects
				(font
					(size 1.27 1.27)
				)
				(justify right)
			)
		)
		(property "Dielectric" "X5R"
			(at 299.72 199.39 0)
			(effects
				(font
					(size 1.27 1.27)
				)
				(justify left bottom)
				(hide yes)
			)
		)
		(property "Public" "False"
			(at 302.26 199.39 0)
			(effects
				(font
					(size 1.27 1.27)
				)
				(justify left bottom)
				(hide yes)
			)
		)
		(pin "1"
		)
		(pin "2"
		)
		(instances
			(project ""
				(path ""
					(reference "C16")
					(unit 1)
				)
			)
		)
	)
	(symbol
		(lib_id "antmicroCapacitors0402:C_33n_0402")
		(at 133.35 228.6 270)
		(unit 1)
		(exclude_from_sim no)
		(in_bom yes)
		(on_board yes)
		(dnp no)
		(property "Reference" "C23"
			(at 135.636 229.87 90)
			(effects
				(font
					(size 1.27 1.27)
				)
				(justify left)
			)
		)
		(property "Value" "C_33n_0402"
			(at 129.54 228.6 0)
			(effects
				(font
					(size 1.27 1.27)
				)
				(justify left)
				(hide yes)
			)
		)
		(property "Footprint" "antmicro-footprints:C_0402_1005Metric"
			(at 138.43 233.68 0)
			(effects
				(font
					(size 1.27 1.27)
					(thickness 0.15)
				)
				(justify left bottom)
				(hide yes)
			)
		)
		(property "Datasheet" "https://www.murata.com/products/productdetail?partno=GCM155R71E333KA55%23"
			(at 133.35 228.6 0)
			(effects
				(font
					(size 1.27 1.27)
					(thickness 0.15)
				)
				(justify left bottom)
				(hide yes)
			)
		)
		(property "Description" "SMD Multilayer Ceramic Capacitor, 33000 pF, 25 V, 0402 [1005 Metric], ± 10%, X7R, MC"
			(at 133.35 228.6 0)
			(effects
				(font
					(size 1.27 1.27)
				)
				(hide yes)
			)
		)
		(property "Manufacturer" "Murata"
			(at 143.51 233.68 0)
			(effects
				(font
					(size 1.27 1.27)
					(thickness 0.15)
				)
				(justify left bottom)
				(hide yes)
			)
		)
		(property "MPN" "GCM155R71E333KA55D"
			(at 140.97 233.68 0)
			(effects
				(font
					(size 1.27 1.27)
					(thickness 0.15)
				)
				(justify left bottom)
				(hide yes)
			)
		)
		(property "Val" "33n"
			(at 135.636 232.4101 90)
			(effects
				(font
					(size 1.27 1.27)
					(thickness 0.15)
				)
				(justify left)
			)
		)
		(property "License" "Apache-2.0"
			(at 110.49 248.92 0)
			(effects
				(font
					(size 1.27 1.27)
					(thickness 0.15)
				)
				(justify left bottom)
				(hide yes)
			)
		)
		(property "Author" "Antmicro"
			(at 107.95 248.92 0)
			(effects
				(font
					(size 1.27 1.27)
					(thickness 0.15)
				)
				(justify left bottom)
				(hide yes)
			)
		)
		(property "Voltage" ""
			(at 105.41 248.92 0)
			(effects
				(font
					(size 1.27 1.27)
				)
				(justify left bottom)
				(hide yes)
			)
		)
		(property "Dielectric" ""
			(at 102.87 248.92 0)
			(effects
				(font
					(size 1.27 1.27)
				)
				(justify left bottom)
				(hide yes)
			)
		)
		(pin "1"
		)
		(pin "2"
		)
		(instances
			(project "oculink-to-pcie-adapter"
				(path ""
					(reference "C23")
					(unit 1)
				)
			)
		)
	)
	(symbol
		(lib_id "antmicropower:GND")
		(at 342.9 109.22 0)
		(unit 1)
		(exclude_from_sim no)
		(in_bom yes)
		(on_board yes)
		(dnp no)
		(property "Reference" "#PWR051"
			(at 351.79 111.76 0)
			(effects
				(font
					(size 1.27 1.27)
					(thickness 0.15)
				)
				(justify left bottom)
				(hide yes)
			)
		)
		(property "Value" "GND"
			(at 342.9 113.03 0)
			(effects
				(font
					(size 1.27 1.27)
					(thickness 0.15)
				)
			)
		)
		(property "Footprint" ""
			(at 351.79 116.84 0)
			(effects
				(font
					(size 1.27 1.27)
					(thickness 0.15)
				)
				(justify left bottom)
				(hide yes)
			)
		)
		(property "Datasheet" ""
			(at 351.79 121.92 0)
			(effects
				(font
					(size 1.27 1.27)
					(thickness 0.15)
				)
				(justify left bottom)
				(hide yes)
			)
		)
		(property "Description" ""
			(at 342.9 109.22 0)
			(effects
				(font
					(size 1.27 1.27)
				)
				(hide yes)
			)
		)
		(property "Author" "Antmicro"
			(at 351.79 116.84 0)
			(effects
				(font
					(size 1.27 1.27)
					(thickness 0.15)
				)
				(justify left bottom)
				(hide yes)
			)
		)
		(property "License" "Apache-2.0"
			(at 351.79 119.38 0)
			(effects
				(font
					(size 1.27 1.27)
					(thickness 0.15)
				)
				(justify left bottom)
				(hide yes)
			)
		)
		(pin "1"
		)
		(instances
			(project "oculink-to-pcie-adapter"
				(path ""
					(reference "#PWR051")
					(unit 1)
				)
			)
		)
	)
	(symbol
		(lib_id "antmicropower:GND")
		(at 250.19 237.49 0)
		(unit 1)
		(exclude_from_sim no)
		(in_bom yes)
		(on_board yes)
		(dnp no)
		(property "Reference" "#PWR078"
			(at 250.19 237.49 0)
			(effects
				(font
					(size 1.27 1.27)
				)
				(justify left)
				(hide yes)
			)
		)
		(property "Value" "GND"
			(at 250.19 241.3 0)
			(effects
				(font
					(size 1.27 1.27)
				)
			)
		)
		(property "Footprint" ""
			(at 250.19 237.49 0)
			(effects
				(font
					(size 1.27 1.27)
					(thickness 0.15)
				)
				(justify left bottom)
				(hide yes)
			)
		)
		(property "Datasheet" ""
			(at 250.19 237.49 0)
			(effects
				(font
					(size 1.27 1.27)
					(thickness 0.15)
				)
				(justify left bottom)
				(hide yes)
			)
		)
		(property "Description" ""
			(at 250.19 237.49 0)
			(effects
				(font
					(size 1.27 1.27)
				)
				(hide yes)
			)
		)
		(property "Author" "Antmicro"
			(at 259.08 245.11 0)
			(effects
				(font
					(size 1.27 1.27)
					(thickness 0.15)
				)
				(justify left bottom)
				(hide yes)
			)
		)
		(property "License" "Apache-2.0"
			(at 259.08 247.65 0)
			(effects
				(font
					(size 1.27 1.27)
					(thickness 0.15)
				)
				(justify left bottom)
				(hide yes)
			)
		)
		(pin "1"
		)
		(instances
			(project "oculink-to-pcie-adapter"
				(path ""
					(reference "#PWR078")
					(unit 1)
				)
			)
		)
	)
	(symbol
		(lib_id "antmicroResistors0402:R_2k_0402")
		(at 223.52 86.36 0)
		(unit 1)
		(exclude_from_sim no)
		(in_bom yes)
		(on_board yes)
		(dnp no)
		(property "Reference" "R18"
			(at 221.996 85.09 0)
			(effects
				(font
					(size 1.27 1.27)
				)
			)
		)
		(property "Value" "R_2k_0402"
			(at 223.52 90.17 0)
			(effects
				(font
					(size 1.27 1.27)
				)
				(justify left)
				(hide yes)
			)
		)
		(property "Footprint" "antmicro-footprints:R_0402_1005Metric"
			(at 228.6 81.28 0)
			(effects
				(font
					(size 1.27 1.27)
					(thickness 0.15)
				)
				(justify left bottom)
				(hide yes)
			)
		)
		(property "Datasheet" "https://www.bourns.com/docs/product-datasheets/cr.pdf"
			(at 223.52 86.36 0)
			(effects
				(font
					(size 1.27 1.27)
					(thickness 0.15)
				)
				(justify left bottom)
				(hide yes)
			)
		)
		(property "Description" "SMD Chip Resistor, 2 kohm, ± 1%, 62.5 mW, 0402 [1005 Metric], Thick Film, General Purpose"
			(at 223.52 86.36 0)
			(effects
				(font
					(size 1.27 1.27)
				)
				(hide yes)
			)
		)
		(property "Manufacturer" "Bourns"
			(at 228.6 76.2 0)
			(effects
				(font
					(size 1.27 1.27)
					(thickness 0.15)
				)
				(justify left bottom)
				(hide yes)
			)
		)
		(property "MPN" "CR0402-FX-2001GLF"
			(at 228.6 78.74 0)
			(effects
				(font
					(size 1.27 1.27)
					(thickness 0.15)
				)
				(justify left bottom)
				(hide yes)
			)
		)
		(property "Val" "2k"
			(at 229.616 85.09 0)
			(effects
				(font
					(size 1.27 1.27)
					(thickness 0.15)
				)
			)
		)
		(property "License" "Apache-2.0"
			(at 243.84 111.76 0)
			(effects
				(font
					(size 1.27 1.27)
					(thickness 0.15)
				)
				(justify left bottom)
				(hide yes)
			)
		)
		(property "Author" "Antmicro"
			(at 243.84 114.3 0)
			(effects
				(font
					(size 1.27 1.27)
					(thickness 0.15)
				)
				(justify left bottom)
				(hide yes)
			)
		)
		(property "Tolerance" "1%"
			(at 243.84 96.52 0)
			(effects
				(font
					(size 1.27 1.27)
				)
				(justify left bottom)
				(hide yes)
			)
		)
		(pin "1"
		)
		(pin "2"
		)
		(instances
			(project "oculink-to-pcie-adapter"
				(path ""
					(reference "R18")
					(unit 1)
				)
			)
		)
	)
	(symbol
		(lib_id "antmicroCapacitorsmisc:C_22u_25V_0805")
		(at 278.13 219.71 90)
		(unit 1)
		(exclude_from_sim no)
		(in_bom yes)
		(on_board yes)
		(dnp no)
		(property "Reference" "C17"
			(at 280.162 214.63 90)
			(effects
				(font
					(size 1.27 1.27)
					(thickness 0.15)
				)
				(justify right)
			)
		)
		(property "Value" "C_22u_25V_0805"
			(at 288.29 199.39 0)
			(effects
				(font
					(size 1.27 1.27)
					(thickness 0.15)
				)
				(justify left bottom)
				(hide yes)
			)
		)
		(property "Footprint" "antmicro-footprints:C_0805_2012Metric"
			(at 290.83 199.39 0)
			(effects
				(font
					(size 1.27 1.27)
					(thickness 0.15)
				)
				(justify left bottom)
				(hide yes)
			)
		)
		(property "Datasheet" "https://product.samsungsem.com/mlcc/CL21A226MAYNNN.do"
			(at 293.37 199.39 0)
			(effects
				(font
					(size 1.27 1.27)
					(thickness 0.15)
				)
				(justify left bottom)
				(hide yes)
			)
		)
		(property "Description" "SMT Multilayer Ceramic Capacitor, 22uF, +/-20%, 25V, X5R, 0805 [2012 Metric]"
			(at 278.13 219.71 0)
			(effects
				(font
					(size 1.27 1.27)
				)
				(hide yes)
			)
		)
		(property "MPN" "CL21A226MAYNNNE"
			(at 295.91 199.39 0)
			(effects
				(font
					(size 1.27 1.27)
					(thickness 0.15)
				)
				(justify left bottom)
				(hide yes)
			)
		)
		(property "Manufacturer" "Samsung Electro-Mechanics"
			(at 298.45 199.39 0)
			(effects
				(font
					(size 1.27 1.27)
					(thickness 0.15)
				)
				(justify left bottom)
				(hide yes)
			)
		)
		(property "License" "Apache-2.0"
			(at 300.99 199.39 0)
			(effects
				(font
					(size 1.27 1.27)
					(thickness 0.15)
				)
				(justify left bottom)
				(hide yes)
			)
		)
		(property "Author" "Antmicro"
			(at 303.53 199.39 0)
			(effects
				(font
					(size 1.27 1.27)
					(thickness 0.15)
				)
				(justify left bottom)
				(hide yes)
			)
		)
		(property "Val" "22u"
			(at 280.162 217.17 90)
			(effects
				(font
					(size 1.27 1.27)
					(thickness 0.15)
				)
				(justify right)
			)
		)
		(property "Voltage" "25V"
			(at 280.162 219.7099 90)
			(effects
				(font
					(size 1.27 1.27)
				)
				(justify right)
			)
		)
		(property "Dielectric" "X5R"
			(at 308.61 199.39 0)
			(effects
				(font
					(size 1.27 1.27)
				)
				(justify left bottom)
				(hide yes)
			)
		)
		(property "Public" "False"
			(at 311.15 199.39 0)
			(effects
				(font
					(size 1.27 1.27)
				)
				(justify left bottom)
				(hide yes)
			)
		)
		(pin "1"
		)
		(pin "2"
		)
		(instances
			(project "oculink-to-pcie-adapter"
				(path ""
					(reference "C17")
					(unit 1)
				)
			)
		)
	)
	(symbol
		(lib_id "antmicropower:GND")
		(at 287.02 237.49 0)
		(unit 1)
		(exclude_from_sim no)
		(in_bom yes)
		(on_board yes)
		(dnp no)
		(property "Reference" "#PWR053"
			(at 287.02 237.49 0)
			(effects
				(font
					(size 1.27 1.27)
				)
				(justify left)
				(hide yes)
			)
		)
		(property "Value" "GND"
			(at 287.02 241.3 0)
			(effects
				(font
					(size 1.27 1.27)
				)
			)
		)
		(property "Footprint" ""
			(at 287.02 237.49 0)
			(effects
				(font
					(size 1.27 1.27)
					(thickness 0.15)
				)
				(justify left bottom)
				(hide yes)
			)
		)
		(property "Datasheet" ""
			(at 287.02 237.49 0)
			(effects
				(font
					(size 1.27 1.27)
					(thickness 0.15)
				)
				(justify left bottom)
				(hide yes)
			)
		)
		(property "Description" ""
			(at 287.02 237.49 0)
			(effects
				(font
					(size 1.27 1.27)
				)
				(hide yes)
			)
		)
		(property "Author" "Antmicro"
			(at 295.91 245.11 0)
			(effects
				(font
					(size 1.27 1.27)
					(thickness 0.15)
				)
				(justify left bottom)
				(hide yes)
			)
		)
		(property "License" "Apache-2.0"
			(at 295.91 247.65 0)
			(effects
				(font
					(size 1.27 1.27)
					(thickness 0.15)
				)
				(justify left bottom)
				(hide yes)
			)
		)
		(pin "1"
		)
		(instances
			(project "oculink-to-pcie-adapter"
				(path ""
					(reference "#PWR053")
					(unit 1)
				)
			)
		)
	)
	(symbol
		(lib_id "antmicroResistors0402:R_1k_0402")
		(at 342.9 68.58 90)
		(unit 1)
		(exclude_from_sim no)
		(in_bom no)
		(on_board yes)
		(dnp yes)
		(property "Reference" "R17"
			(at 344.17 64.77 90)
			(effects
				(font
					(size 1.27 1.27)
					(thickness 0.15)
				)
				(justify right)
			)
		)
		(property "Value" "R_1k_0402"
			(at 355.6 48.26 0)
			(effects
				(font
					(size 1.27 1.27)
					(thickness 0.15)
				)
				(justify left bottom)
				(hide yes)
			)
		)
		(property "Footprint" "antmicro-footprints:R_0402_1005Metric"
			(at 358.14 48.26 0)
			(effects
				(font
					(size 1.27 1.27)
					(thickness 0.15)
				)
				(justify left bottom)
				(hide yes)
			)
		)
		(property "Datasheet" "https://www.bourns.com/docs/product-datasheets/cr.pdf"
			(at 360.68 48.26 0)
			(effects
				(font
					(size 1.27 1.27)
					(thickness 0.15)
				)
				(justify left bottom)
				(hide yes)
			)
		)
		(property "Description" "SMD Chip Resistor, 1 kohm, ± 1%, 63 mW, 0402 [1005 Metric], Thick Film, General Purpose"
			(at 342.9 68.58 0)
			(effects
				(font
					(size 1.27 1.27)
				)
				(hide yes)
			)
		)
		(property "MPN" "CR0402-FX-1001GLF"
			(at 363.22 48.26 0)
			(effects
				(font
					(size 1.27 1.27)
					(thickness 0.15)
				)
				(justify left bottom)
				(hide yes)
			)
		)
		(property "Manufacturer" "Bourns"
			(at 365.76 48.26 0)
			(effects
				(font
					(size 1.27 1.27)
					(thickness 0.15)
				)
				(justify left bottom)
				(hide yes)
			)
		)
		(property "License" "Apache-2.0"
			(at 368.3 48.26 0)
			(effects
				(font
					(size 1.27 1.27)
					(thickness 0.15)
				)
				(justify left bottom)
				(hide yes)
			)
		)
		(property "Author" "Antmicro"
			(at 370.84 48.26 0)
			(effects
				(font
					(size 1.27 1.27)
					(thickness 0.15)
				)
				(justify left bottom)
				(hide yes)
			)
		)
		(property "Val" "1k"
			(at 344.17 67.31 90)
			(effects
				(font
					(size 1.27 1.27)
					(thickness 0.15)
				)
				(justify right)
			)
		)
		(property "Tolerance" "1%"
			(at 353.06 48.26 0)
			(effects
				(font
					(size 1.27 1.27)
				)
				(justify left bottom)
				(hide yes)
			)
		)
		(pin "2"
		)
		(pin "1"
		)
		(instances
			(project "oculink-to-pcie-adapter"
				(path ""
					(reference "R17")
					(unit 1)
				)
			)
		)
	)
	(symbol
		(lib_id "antmicropower:GND")
		(at 102.87 101.6 0)
		(unit 1)
		(exclude_from_sim no)
		(in_bom yes)
		(on_board yes)
		(dnp no)
		(property "Reference" "#PWR038"
			(at 111.76 104.14 0)
			(effects
				(font
					(size 1.27 1.27)
					(thickness 0.15)
				)
				(justify left bottom)
				(hide yes)
			)
		)
		(property "Value" "GND"
			(at 102.87 105.41 0)
			(effects
				(font
					(size 1.27 1.27)
					(thickness 0.15)
				)
			)
		)
		(property "Footprint" ""
			(at 111.76 109.22 0)
			(effects
				(font
					(size 1.27 1.27)
					(thickness 0.15)
				)
				(justify left bottom)
				(hide yes)
			)
		)
		(property "Datasheet" ""
			(at 111.76 114.3 0)
			(effects
				(font
					(size 1.27 1.27)
					(thickness 0.15)
				)
				(justify left bottom)
				(hide yes)
			)
		)
		(property "Description" ""
			(at 102.87 101.6 0)
			(effects
				(font
					(size 1.27 1.27)
				)
				(hide yes)
			)
		)
		(property "Author" "Antmicro"
			(at 111.76 109.22 0)
			(effects
				(font
					(size 1.27 1.27)
					(thickness 0.15)
				)
				(justify left bottom)
				(hide yes)
			)
		)
		(property "License" "Apache-2.0"
			(at 111.76 111.76 0)
			(effects
				(font
					(size 1.27 1.27)
					(thickness 0.15)
				)
				(justify left bottom)
				(hide yes)
			)
		)
		(pin "1"
		)
		(instances
			(project "oculink-to-pcie-adapter"
				(path ""
					(reference "#PWR038")
					(unit 1)
				)
			)
		)
	)
	(symbol
		(lib_id "antmicropower:VBUS")
		(at 172.72 50.8 0)
		(mirror y)
		(unit 1)
		(exclude_from_sim no)
		(in_bom yes)
		(on_board yes)
		(dnp no)
		(property "Reference" "#PWR0100"
			(at 172.72 54.61 0)
			(effects
				(font
					(size 1.27 1.27)
				)
				(hide yes)
			)
		)
		(property "Value" "VBUS"
			(at 172.72 46.99 0)
			(effects
				(font
					(size 1.27 1.27)
				)
			)
		)
		(property "Footprint" ""
			(at 172.72 50.8 0)
			(effects
				(font
					(size 1.27 1.27)
				)
				(hide yes)
			)
		)
		(property "Datasheet" ""
			(at 172.72 50.8 0)
			(effects
				(font
					(size 1.27 1.27)
				)
				(hide yes)
			)
		)
		(property "Description" ""
			(at 172.72 50.8 0)
			(effects
				(font
					(size 1.27 1.27)
				)
				(hide yes)
			)
		)
		(pin "1"
		)
		(instances
			(project "oculink-to-pcie-adapter"
				(path ""
					(reference "#PWR0100")
					(unit 1)
				)
			)
		)
	)
	(symbol
		(lib_id "antmicroCapacitors0402:C_1u_25V_0402")
		(at 132.08 116.84 90)
		(unit 1)
		(exclude_from_sim no)
		(in_bom yes)
		(on_board yes)
		(dnp no)
		(property "Reference" "C39"
			(at 134.112 113.03 90)
			(effects
				(font
					(size 1.27 1.27)
					(thickness 0.15)
				)
				(justify right)
			)
		)
		(property "Value" "C_1u_25V_0402"
			(at 142.24 96.52 0)
			(effects
				(font
					(size 1.27 1.27)
					(thickness 0.15)
				)
				(justify left bottom)
				(hide yes)
			)
		)
		(property "Footprint" "antmicro-footprints:C_0402_1005Metric"
			(at 144.78 96.52 0)
			(effects
				(font
					(size 1.27 1.27)
					(thickness 0.15)
				)
				(justify left bottom)
				(hide yes)
			)
		)
		(property "Datasheet" "https://www.murata.com/products/productdetail?partno=GRM155R61E105KE11%23"
			(at 147.32 96.52 0)
			(effects
				(font
					(size 1.27 1.27)
					(thickness 0.15)
				)
				(justify left bottom)
				(hide yes)
			)
		)
		(property "Description" "SMD Multilayer Ceramic Capacitor, 1 µF, 25 V, 0402 [1005 Metric], ± 10%, X5R, GRM Series"
			(at 132.08 116.84 0)
			(effects
				(font
					(size 1.27 1.27)
				)
				(hide yes)
			)
		)
		(property "MPN" "GRM155R61E105KE11J"
			(at 149.86 96.52 0)
			(effects
				(font
					(size 1.27 1.27)
					(thickness 0.15)
				)
				(justify left bottom)
				(hide yes)
			)
		)
		(property "Manufacturer" "Murata"
			(at 152.4 96.52 0)
			(effects
				(font
					(size 1.27 1.27)
					(thickness 0.15)
				)
				(justify left bottom)
				(hide yes)
			)
		)
		(property "License" "Apache-2.0"
			(at 154.94 96.52 0)
			(effects
				(font
					(size 1.27 1.27)
					(thickness 0.15)
				)
				(justify left bottom)
				(hide yes)
			)
		)
		(property "Author" "Antmicro"
			(at 157.48 96.52 0)
			(effects
				(font
					(size 1.27 1.27)
					(thickness 0.15)
				)
				(justify left bottom)
				(hide yes)
			)
		)
		(property "Val" "1u"
			(at 134.112 115.57 90)
			(effects
				(font
					(size 1.27 1.27)
					(thickness 0.15)
				)
				(justify right)
			)
		)
		(property "Voltage" "25V"
			(at 160.02 96.52 0)
			(effects
				(font
					(size 1.27 1.27)
				)
				(justify left bottom)
				(hide yes)
			)
		)
		(property "Dielectric" "X5R"
			(at 162.56 96.52 0)
			(effects
				(font
					(size 1.27 1.27)
				)
				(justify left bottom)
				(hide yes)
			)
		)
		(pin "1"
		)
		(pin "2"
		)
		(instances
			(project "oculink-to-pcie-adapter"
				(path ""
					(reference "C39")
					(unit 1)
				)
			)
		)
	)
	(symbol
		(lib_id "antmicropower:GND")
		(at 165.1 237.49 0)
		(unit 1)
		(exclude_from_sim no)
		(in_bom yes)
		(on_board yes)
		(dnp no)
		(property "Reference" "#PWR074"
			(at 165.1 237.49 0)
			(effects
				(font
					(size 1.27 1.27)
				)
				(justify left)
				(hide yes)
			)
		)
		(property "Value" "GND"
			(at 165.1 241.3 0)
			(effects
				(font
					(size 1.27 1.27)
				)
			)
		)
		(property "Footprint" ""
			(at 165.1 237.49 0)
			(effects
				(font
					(size 1.27 1.27)
					(thickness 0.15)
				)
				(justify left bottom)
				(hide yes)
			)
		)
		(property "Datasheet" ""
			(at 165.1 237.49 0)
			(effects
				(font
					(size 1.27 1.27)
					(thickness 0.15)
				)
				(justify left bottom)
				(hide yes)
			)
		)
		(property "Description" ""
			(at 165.1 237.49 0)
			(effects
				(font
					(size 1.27 1.27)
				)
				(hide yes)
			)
		)
		(property "Author" "Antmicro"
			(at 173.99 245.11 0)
			(effects
				(font
					(size 1.27 1.27)
					(thickness 0.15)
				)
				(justify left bottom)
				(hide yes)
			)
		)
		(property "License" "Apache-2.0"
			(at 173.99 247.65 0)
			(effects
				(font
					(size 1.27 1.27)
					(thickness 0.15)
				)
				(justify left bottom)
				(hide yes)
			)
		)
		(pin "1"
		)
		(instances
			(project "oculink-to-pcie-adapter"
				(path ""
					(reference "#PWR074")
					(unit 1)
				)
			)
		)
	)
	(symbol
		(lib_id "antmicropower:GND")
		(at 151.13 119.38 0)
		(unit 1)
		(exclude_from_sim no)
		(in_bom yes)
		(on_board yes)
		(dnp no)
		(property "Reference" "#PWR049"
			(at 160.02 121.92 0)
			(effects
				(font
					(size 1.27 1.27)
					(thickness 0.15)
				)
				(justify left bottom)
				(hide yes)
			)
		)
		(property "Value" "GND"
			(at 151.13 123.19 0)
			(effects
				(font
					(size 1.27 1.27)
					(thickness 0.15)
				)
			)
		)
		(property "Footprint" ""
			(at 160.02 127 0)
			(effects
				(font
					(size 1.27 1.27)
					(thickness 0.15)
				)
				(justify left bottom)
				(hide yes)
			)
		)
		(property "Datasheet" ""
			(at 160.02 132.08 0)
			(effects
				(font
					(size 1.27 1.27)
					(thickness 0.15)
				)
				(justify left bottom)
				(hide yes)
			)
		)
		(property "Description" ""
			(at 151.13 119.38 0)
			(effects
				(font
					(size 1.27 1.27)
				)
				(hide yes)
			)
		)
		(property "Author" "Antmicro"
			(at 160.02 127 0)
			(effects
				(font
					(size 1.27 1.27)
					(thickness 0.15)
				)
				(justify left bottom)
				(hide yes)
			)
		)
		(property "License" "Apache-2.0"
			(at 160.02 129.54 0)
			(effects
				(font
					(size 1.27 1.27)
					(thickness 0.15)
				)
				(justify left bottom)
				(hide yes)
			)
		)
		(pin "1"
		)
		(instances
			(project "oculink-to-pcie-adapter"
				(path ""
					(reference "#PWR049")
					(unit 1)
				)
			)
		)
	)
	(symbol
		(lib_id "antmicroCapacitorsmisc:C_22u_25V_0805")
		(at 295.91 219.71 90)
		(unit 1)
		(exclude_from_sim no)
		(in_bom yes)
		(on_board yes)
		(dnp no)
		(property "Reference" "C19"
			(at 297.942 214.63 90)
			(effects
				(font
					(size 1.27 1.27)
					(thickness 0.15)
				)
				(justify right)
			)
		)
		(property "Value" "C_22u_25V_0805"
			(at 306.07 199.39 0)
			(effects
				(font
					(size 1.27 1.27)
					(thickness 0.15)
				)
				(justify left bottom)
				(hide yes)
			)
		)
		(property "Footprint" "antmicro-footprints:C_0805_2012Metric"
			(at 308.61 199.39 0)
			(effects
				(font
					(size 1.27 1.27)
					(thickness 0.15)
				)
				(justify left bottom)
				(hide yes)
			)
		)
		(property "Datasheet" "https://product.samsungsem.com/mlcc/CL21A226MAYNNN.do"
			(at 311.15 199.39 0)
			(effects
				(font
					(size 1.27 1.27)
					(thickness 0.15)
				)
				(justify left bottom)
				(hide yes)
			)
		)
		(property "Description" "SMT Multilayer Ceramic Capacitor, 22uF, +/-20%, 25V, X5R, 0805 [2012 Metric]"
			(at 295.91 219.71 0)
			(effects
				(font
					(size 1.27 1.27)
				)
				(hide yes)
			)
		)
		(property "MPN" "CL21A226MAYNNNE"
			(at 313.69 199.39 0)
			(effects
				(font
					(size 1.27 1.27)
					(thickness 0.15)
				)
				(justify left bottom)
				(hide yes)
			)
		)
		(property "Manufacturer" "Samsung Electro-Mechanics"
			(at 316.23 199.39 0)
			(effects
				(font
					(size 1.27 1.27)
					(thickness 0.15)
				)
				(justify left bottom)
				(hide yes)
			)
		)
		(property "License" "Apache-2.0"
			(at 318.77 199.39 0)
			(effects
				(font
					(size 1.27 1.27)
					(thickness 0.15)
				)
				(justify left bottom)
				(hide yes)
			)
		)
		(property "Author" "Antmicro"
			(at 321.31 199.39 0)
			(effects
				(font
					(size 1.27 1.27)
					(thickness 0.15)
				)
				(justify left bottom)
				(hide yes)
			)
		)
		(property "Val" "22u"
			(at 297.942 217.17 90)
			(effects
				(font
					(size 1.27 1.27)
					(thickness 0.15)
				)
				(justify right)
			)
		)
		(property "Voltage" "25V"
			(at 297.942 219.7099 90)
			(effects
				(font
					(size 1.27 1.27)
				)
				(justify right)
			)
		)
		(property "Dielectric" "X5R"
			(at 326.39 199.39 0)
			(effects
				(font
					(size 1.27 1.27)
				)
				(justify left bottom)
				(hide yes)
			)
		)
		(property "Public" "False"
			(at 328.93 199.39 0)
			(effects
				(font
					(size 1.27 1.27)
				)
				(justify left bottom)
				(hide yes)
			)
		)
		(pin "1"
		)
		(pin "2"
		)
		(instances
			(project "oculink-to-pcie-adapter"
				(path ""
					(reference "C19")
					(unit 1)
				)
			)
		)
	)
	(symbol
		(lib_id "antmicroTestPoints:TP_Pad0.75mm_Drill0.2mm")
		(at 106.68 62.23 90)
		(unit 1)
		(exclude_from_sim no)
		(in_bom no)
		(on_board yes)
		(dnp no)
		(property "Reference" "TP4"
			(at 107.95 59.055 90)
			(effects
				(font
					(size 1.27 1.27)
					(thickness 0.15)
				)
				(justify right)
			)
		)
		(property "Value" "TP_Pad0.75mm_Drill0.2mm"
			(at 110.49 52.07 0)
			(effects
				(font
					(size 1.27 1.27)
					(thickness 0.15)
				)
				(justify left bottom)
				(hide yes)
			)
		)
		(property "Footprint" "antmicro-footprints:TP_Pad0.75mm_Drill0.2mm"
			(at 113.03 52.07 0)
			(effects
				(font
					(size 1.27 1.27)
					(thickness 0.15)
				)
				(justify left bottom)
				(hide yes)
			)
		)
		(property "Datasheet" ""
			(at 119.38 44.45 0)
			(effects
				(font
					(size 1.27 1.27)
					(thickness 0.15)
				)
				(justify left bottom)
				(hide yes)
			)
		)
		(property "Description" "SMT test point"
			(at 106.68 62.23 0)
			(effects
				(font
					(size 1.27 1.27)
				)
				(hide yes)
			)
		)
		(property "MPN" ""
			(at 118.11 51.435 0)
			(effects
				(font
					(size 1.27 1.27)
					(thickness 0.15)
				)
				(justify left bottom)
				(hide yes)
			)
		)
		(property "Manufacturer" ""
			(at 113.03 51.435 0)
			(effects
				(font
					(size 1.27 1.27)
					(thickness 0.15)
				)
				(justify left bottom)
				(hide yes)
			)
		)
		(property "Author" "Antmicro"
			(at 115.57 52.07 0)
			(effects
				(font
					(size 1.27 1.27)
					(thickness 0.15)
				)
				(justify left bottom)
				(hide yes)
			)
		)
		(property "License" "Apache-2.0"
			(at 118.11 52.07 0)
			(effects
				(font
					(size 1.27 1.27)
					(thickness 0.15)
				)
				(justify left bottom)
				(hide yes)
			)
		)
		(pin "1"
		)
		(instances
			(project "oculink-to-pcie-adapter"
				(path ""
					(reference "TP4")
					(unit 1)
				)
			)
		)
	)
	(symbol
		(lib_id "antmicropower:VBUS")
		(at 114.3 60.96 0)
		(unit 1)
		(exclude_from_sim no)
		(in_bom yes)
		(on_board yes)
		(dnp no)
		(property "Reference" "#PWR037"
			(at 114.3 64.77 0)
			(effects
				(font
					(size 1.27 1.27)
				)
				(hide yes)
			)
		)
		(property "Value" "VBUS"
			(at 114.3 57.15 0)
			(effects
				(font
					(size 1.27 1.27)
				)
			)
		)
		(property "Footprint" ""
			(at 114.3 60.96 0)
			(effects
				(font
					(size 1.27 1.27)
				)
				(hide yes)
			)
		)
		(property "Datasheet" ""
			(at 114.3 60.96 0)
			(effects
				(font
					(size 1.27 1.27)
				)
				(hide yes)
			)
		)
		(property "Description" ""
			(at 114.3 60.96 0)
			(effects
				(font
					(size 1.27 1.27)
				)
				(hide yes)
			)
		)
		(pin "1"
		)
		(instances
			(project "oculink-to-pcie-adapter"
				(path ""
					(reference "#PWR037")
					(unit 1)
				)
			)
		)
	)
	(symbol
		(lib_id "antmicroCapacitorspol:C_Pol_150u_30V_Vishay-T59-EE")
		(at 105.41 196.85 270)
		(unit 1)
		(exclude_from_sim no)
		(in_bom yes)
		(on_board yes)
		(dnp no)
		(fields_autoplaced yes)
		(property "Reference" "C44"
			(at 107.95 197.5866 90)
			(effects
				(font
					(size 1.27 1.27)
					(thickness 0.15)
				)
				(justify left)
			)
		)
		(property "Value" "C_Pol_150u_30V_Vishay-T59-EE"
			(at 95.25 212.09 0)
			(effects
				(font
					(size 1.27 1.27)
					(thickness 0.15)
				)
				(justify left bottom)
				(hide yes)
			)
		)
		(property "Footprint" "antmicro-footprints:C_Pol_Vishay-T59-EE"
			(at 92.71 212.09 0)
			(effects
				(font
					(size 1.27 1.27)
					(thickness 0.15)
				)
				(justify left bottom)
				(hide yes)
			)
		)
		(property "Datasheet" "https://www.vishay.com/docs/40191/t59.pdf"
			(at 90.17 212.09 0)
			(effects
				(font
					(size 1.27 1.27)
					(thickness 0.15)
				)
				(justify left bottom)
				(hide yes)
			)
		)
		(property "Description" "Tantalum Capacitors - Polymer 150uF 30volts 20% 75mohms maxESR"
			(at 105.41 196.85 0)
			(effects
				(font
					(size 1.27 1.27)
				)
				(hide yes)
			)
		)
		(property "MPN" "T59EE157M030C0075"
			(at 92.71 210.82 0)
			(effects
				(font
					(size 1.27 1.27)
				)
				(justify left bottom)
				(hide yes)
			)
		)
		(property "Manufacturer" "Vishay"
			(at 87.63 212.09 0)
			(effects
				(font
					(size 1.27 1.27)
					(thickness 0.15)
				)
				(justify left bottom)
				(hide yes)
			)
		)
		(property "Voltage" "30V"
			(at 85.09 212.09 0)
			(effects
				(font
					(size 1.27 1.27)
					(thickness 0.15)
				)
				(justify left bottom)
				(hide yes)
			)
		)
		(property "Val" "150u"
			(at 107.95 200.1266 90)
			(effects
				(font
					(size 1.27 1.27)
					(thickness 0.15)
				)
				(justify left)
			)
		)
		(property "Author" "Antmicro"
			(at 82.55 212.09 0)
			(effects
				(font
					(size 1.27 1.27)
					(thickness 0.15)
				)
				(justify left bottom)
				(hide yes)
			)
		)
		(property "License" "Apache-2.0"
			(at 80.01 212.09 0)
			(effects
				(font
					(size 1.27 1.27)
					(thickness 0.15)
				)
				(justify left bottom)
				(hide yes)
			)
		)
		(property "Dielectric" "template_dielectric"
			(at 80.01 210.82 0)
			(effects
				(font
					(size 1.27 1.27)
				)
				(justify left bottom)
				(hide yes)
			)
		)
		(pin "2"
		)
		(pin "1"
		)
		(instances
			(project "oculink-to-pcie-adapter"
				(path ""
					(reference "C44")
					(unit 1)
				)
			)
		)
	)
	(symbol
		(lib_id "antmicropower:GND")
		(at 125.73 237.49 0)
		(unit 1)
		(exclude_from_sim no)
		(in_bom yes)
		(on_board yes)
		(dnp no)
		(property "Reference" "#PWR068"
			(at 125.73 237.49 0)
			(effects
				(font
					(size 1.27 1.27)
				)
				(justify left)
				(hide yes)
			)
		)
		(property "Value" "GND"
			(at 125.73 241.3 0)
			(effects
				(font
					(size 1.27 1.27)
				)
			)
		)
		(property "Footprint" ""
			(at 125.73 237.49 0)
			(effects
				(font
					(size 1.27 1.27)
					(thickness 0.15)
				)
				(justify left bottom)
				(hide yes)
			)
		)
		(property "Datasheet" ""
			(at 125.73 237.49 0)
			(effects
				(font
					(size 1.27 1.27)
					(thickness 0.15)
				)
				(justify left bottom)
				(hide yes)
			)
		)
		(property "Description" ""
			(at 125.73 237.49 0)
			(effects
				(font
					(size 1.27 1.27)
				)
				(hide yes)
			)
		)
		(property "Author" "Antmicro"
			(at 134.62 245.11 0)
			(effects
				(font
					(size 1.27 1.27)
					(thickness 0.15)
				)
				(justify left bottom)
				(hide yes)
			)
		)
		(property "License" "Apache-2.0"
			(at 134.62 247.65 0)
			(effects
				(font
					(size 1.27 1.27)
					(thickness 0.15)
				)
				(justify left bottom)
				(hide yes)
			)
		)
		(pin "1"
		)
		(instances
			(project "oculink-to-pcie-adapter"
				(path ""
					(reference "#PWR068")
					(unit 1)
				)
			)
		)
	)
	(symbol
		(lib_id "antmicroResistors0402:R_2k_0402")
		(at 223.52 88.9 0)
		(unit 1)
		(exclude_from_sim no)
		(in_bom yes)
		(on_board yes)
		(dnp no)
		(property "Reference" "R19"
			(at 221.996 87.63 0)
			(effects
				(font
					(size 1.27 1.27)
				)
			)
		)
		(property "Value" "R_2k_0402"
			(at 223.52 92.71 0)
			(effects
				(font
					(size 1.27 1.27)
				)
				(justify left)
				(hide yes)
			)
		)
		(property "Footprint" "antmicro-footprints:R_0402_1005Metric"
			(at 228.6 83.82 0)
			(effects
				(font
					(size 1.27 1.27)
					(thickness 0.15)
				)
				(justify left bottom)
				(hide yes)
			)
		)
		(property "Datasheet" "https://www.bourns.com/docs/product-datasheets/cr.pdf"
			(at 223.52 88.9 0)
			(effects
				(font
					(size 1.27 1.27)
					(thickness 0.15)
				)
				(justify left bottom)
				(hide yes)
			)
		)
		(property "Description" "SMD Chip Resistor, 2 kohm, ± 1%, 62.5 mW, 0402 [1005 Metric], Thick Film, General Purpose"
			(at 223.52 88.9 0)
			(effects
				(font
					(size 1.27 1.27)
				)
				(hide yes)
			)
		)
		(property "Manufacturer" "Bourns"
			(at 228.6 78.74 0)
			(effects
				(font
					(size 1.27 1.27)
					(thickness 0.15)
				)
				(justify left bottom)
				(hide yes)
			)
		)
		(property "MPN" "CR0402-FX-2001GLF"
			(at 228.6 81.28 0)
			(effects
				(font
					(size 1.27 1.27)
					(thickness 0.15)
				)
				(justify left bottom)
				(hide yes)
			)
		)
		(property "Val" "2k"
			(at 229.616 87.63 0)
			(effects
				(font
					(size 1.27 1.27)
					(thickness 0.15)
				)
			)
		)
		(property "License" "Apache-2.0"
			(at 243.84 114.3 0)
			(effects
				(font
					(size 1.27 1.27)
					(thickness 0.15)
				)
				(justify left bottom)
				(hide yes)
			)
		)
		(property "Author" "Antmicro"
			(at 243.84 116.84 0)
			(effects
				(font
					(size 1.27 1.27)
					(thickness 0.15)
				)
				(justify left bottom)
				(hide yes)
			)
		)
		(property "Tolerance" "1%"
			(at 243.84 99.06 0)
			(effects
				(font
					(size 1.27 1.27)
				)
				(justify left bottom)
				(hide yes)
			)
		)
		(pin "1"
		)
		(pin "2"
		)
		(instances
			(project "oculink-to-pcie-adapter"
				(path ""
					(reference "R19")
					(unit 1)
				)
			)
		)
	)
	(symbol
		(lib_id "antmicroCapacitors0402:C_1u_25V_0402")
		(at 227.33 60.96 90)
		(unit 1)
		(exclude_from_sim no)
		(in_bom yes)
		(on_board yes)
		(dnp no)
		(property "Reference" "C10"
			(at 229.362 57.15 90)
			(effects
				(font
					(size 1.27 1.27)
					(thickness 0.15)
				)
				(justify right)
			)
		)
		(property "Value" "C_1u_25V_0402"
			(at 237.49 40.64 0)
			(effects
				(font
					(size 1.27 1.27)
					(thickness 0.15)
				)
				(justify left bottom)
				(hide yes)
			)
		)
		(property "Footprint" "antmicro-footprints:C_0402_1005Metric"
			(at 240.03 40.64 0)
			(effects
				(font
					(size 1.27 1.27)
					(thickness 0.15)
				)
				(justify left bottom)
				(hide yes)
			)
		)
		(property "Datasheet" "https://www.murata.com/products/productdetail?partno=GRM155R61E105KE11%23"
			(at 242.57 40.64 0)
			(effects
				(font
					(size 1.27 1.27)
					(thickness 0.15)
				)
				(justify left bottom)
				(hide yes)
			)
		)
		(property "Description" "SMD Multilayer Ceramic Capacitor, 1 µF, 25 V, 0402 [1005 Metric], ± 10%, X5R, GRM Series"
			(at 227.33 60.96 0)
			(effects
				(font
					(size 1.27 1.27)
				)
				(hide yes)
			)
		)
		(property "MPN" "GRM155R61E105KE11J"
			(at 245.11 40.64 0)
			(effects
				(font
					(size 1.27 1.27)
					(thickness 0.15)
				)
				(justify left bottom)
				(hide yes)
			)
		)
		(property "Manufacturer" "Murata"
			(at 247.65 40.64 0)
			(effects
				(font
					(size 1.27 1.27)
					(thickness 0.15)
				)
				(justify left bottom)
				(hide yes)
			)
		)
		(property "License" "Apache-2.0"
			(at 250.19 40.64 0)
			(effects
				(font
					(size 1.27 1.27)
					(thickness 0.15)
				)
				(justify left bottom)
				(hide yes)
			)
		)
		(property "Author" "Antmicro"
			(at 252.73 40.64 0)
			(effects
				(font
					(size 1.27 1.27)
					(thickness 0.15)
				)
				(justify left bottom)
				(hide yes)
			)
		)
		(property "Val" "1u"
			(at 229.362 59.69 90)
			(effects
				(font
					(size 1.27 1.27)
					(thickness 0.15)
				)
				(justify right)
			)
		)
		(property "Voltage" "25V"
			(at 255.27 40.64 0)
			(effects
				(font
					(size 1.27 1.27)
				)
				(justify left bottom)
				(hide yes)
			)
		)
		(property "Dielectric" "X5R"
			(at 257.81 40.64 0)
			(effects
				(font
					(size 1.27 1.27)
				)
				(justify left bottom)
				(hide yes)
			)
		)
		(pin "1"
		)
		(pin "2"
		)
		(instances
			(project "oculink-to-pcie-adapter"
				(path ""
					(reference "C10")
					(unit 1)
				)
			)
		)
	)
	(symbol
		(lib_id "antmicropower:GND")
		(at 161.29 119.38 0)
		(unit 1)
		(exclude_from_sim no)
		(in_bom yes)
		(on_board yes)
		(dnp no)
		(property "Reference" "#PWR045"
			(at 170.18 121.92 0)
			(effects
				(font
					(size 1.27 1.27)
					(thickness 0.15)
				)
				(justify left bottom)
				(hide yes)
			)
		)
		(property "Value" "GND"
			(at 161.29 123.19 0)
			(effects
				(font
					(size 1.27 1.27)
					(thickness 0.15)
				)
			)
		)
		(property "Footprint" ""
			(at 170.18 127 0)
			(effects
				(font
					(size 1.27 1.27)
					(thickness 0.15)
				)
				(justify left bottom)
				(hide yes)
			)
		)
		(property "Datasheet" ""
			(at 170.18 132.08 0)
			(effects
				(font
					(size 1.27 1.27)
					(thickness 0.15)
				)
				(justify left bottom)
				(hide yes)
			)
		)
		(property "Description" ""
			(at 161.29 119.38 0)
			(effects
				(font
					(size 1.27 1.27)
				)
				(hide yes)
			)
		)
		(property "Author" "Antmicro"
			(at 170.18 127 0)
			(effects
				(font
					(size 1.27 1.27)
					(thickness 0.15)
				)
				(justify left bottom)
				(hide yes)
			)
		)
		(property "License" "Apache-2.0"
			(at 170.18 129.54 0)
			(effects
				(font
					(size 1.27 1.27)
					(thickness 0.15)
				)
				(justify left bottom)
				(hide yes)
			)
		)
		(pin "1"
		)
		(instances
			(project "oculink-to-pcie-adapter"
				(path ""
					(reference "#PWR045")
					(unit 1)
				)
			)
		)
	)
	(symbol
		(lib_id "antmicropower:GND")
		(at 312.42 133.35 0)
		(mirror y)
		(unit 1)
		(exclude_from_sim no)
		(in_bom yes)
		(on_board yes)
		(dnp no)
		(property "Reference" "#PWR054"
			(at 303.53 135.89 0)
			(effects
				(font
					(size 1.27 1.27)
					(thickness 0.15)
				)
				(justify left bottom)
				(hide yes)
			)
		)
		(property "Value" "GND"
			(at 312.42 137.16 0)
			(effects
				(font
					(size 1.27 1.27)
					(thickness 0.15)
				)
			)
		)
		(property "Footprint" ""
			(at 303.53 140.97 0)
			(effects
				(font
					(size 1.27 1.27)
					(thickness 0.15)
				)
				(justify left bottom)
				(hide yes)
			)
		)
		(property "Datasheet" ""
			(at 303.53 146.05 0)
			(effects
				(font
					(size 1.27 1.27)
					(thickness 0.15)
				)
				(justify left bottom)
				(hide yes)
			)
		)
		(property "Description" ""
			(at 312.42 133.35 0)
			(effects
				(font
					(size 1.27 1.27)
				)
				(hide yes)
			)
		)
		(property "Author" "Antmicro"
			(at 303.53 140.97 0)
			(effects
				(font
					(size 1.27 1.27)
					(thickness 0.15)
				)
				(justify left bottom)
				(hide yes)
			)
		)
		(property "License" "Apache-2.0"
			(at 303.53 143.51 0)
			(effects
				(font
					(size 1.27 1.27)
					(thickness 0.15)
				)
				(justify left bottom)
				(hide yes)
			)
		)
		(pin "1"
		)
		(instances
			(project "oculink-to-pcie-adapter"
				(path ""
					(reference "#PWR054")
					(unit 1)
				)
			)
		)
	)
)
